G04*
G04 #@! TF.GenerationSoftware,Altium Limited,Altium Designer,23.6.0 (18)*
G04*
G04 Layer_Color=32896*
%FSLAX44Y44*%
%MOMM*%
G71*
G04*
G04 #@! TF.SameCoordinates,0D6CC9A4-690D-4EF8-AA6E-9FB67146BD04*
G04*
G04*
G04 #@! TF.FilePolarity,Positive*
G04*
G01*
G75*
%ADD11C,0.4500*%
%ADD14C,0.1000*%
%ADD73C,0.3000*%
%ADD101R,15.0000X5.0000*%
G36*
X33745Y292433D02*
X33980Y292410D01*
X34203Y292386D01*
X34402Y292363D01*
X34590Y292339D01*
X34766Y292304D01*
X34919Y292269D01*
X35048Y292234D01*
X35165Y292210D01*
X35271Y292175D01*
X35353Y292152D01*
X35412Y292128D01*
X35458Y292105D01*
X35482Y292093D01*
X35494D01*
X35775Y291952D01*
X36022Y291800D01*
X36233Y291623D01*
X36409Y291471D01*
X36538Y291318D01*
X36632Y291201D01*
X36667Y291154D01*
X36691Y291119D01*
X36714Y291107D01*
Y291095D01*
X36855Y290849D01*
X36960Y290603D01*
X37043Y290356D01*
X37090Y290133D01*
X37125Y289934D01*
X37136Y289851D01*
Y289793D01*
X37148Y289734D01*
Y289652D01*
X37136Y289453D01*
X37113Y289265D01*
X37078Y289077D01*
X37031Y288913D01*
X36902Y288596D01*
X36843Y288455D01*
X36773Y288338D01*
X36691Y288220D01*
X36632Y288127D01*
X36562Y288033D01*
X36503Y287962D01*
X36456Y287904D01*
X36421Y287868D01*
X36397Y287845D01*
X36386Y287833D01*
X36245Y287704D01*
X36080Y287598D01*
X35928Y287493D01*
X35763Y287411D01*
X35587Y287340D01*
X35423Y287282D01*
X35118Y287199D01*
X34966Y287164D01*
X34836Y287141D01*
X34707Y287129D01*
X34602Y287117D01*
X34520Y287106D01*
X34461D01*
X34414D01*
X34402D01*
X34179Y287117D01*
X33980Y287141D01*
X33780Y287164D01*
X33593Y287211D01*
X33428Y287270D01*
X33264Y287329D01*
X33123Y287387D01*
X32994Y287458D01*
X32877Y287516D01*
X32771Y287575D01*
X32689Y287634D01*
X32607Y287692D01*
X32548Y287739D01*
X32513Y287763D01*
X32490Y287786D01*
X32478Y287798D01*
X32349Y287927D01*
X32243Y288068D01*
X32137Y288209D01*
X32055Y288361D01*
X31985Y288502D01*
X31926Y288643D01*
X31844Y288913D01*
X31809Y289030D01*
X31785Y289147D01*
X31774Y289241D01*
X31762Y289335D01*
X31750Y289406D01*
Y289499D01*
X31762Y289722D01*
X31797Y289934D01*
X31844Y290121D01*
X31903Y290298D01*
X31950Y290427D01*
X31997Y290532D01*
X32032Y290603D01*
X32044Y290626D01*
X32161Y290814D01*
X32290Y290978D01*
X32419Y291119D01*
X32536Y291236D01*
X32654Y291318D01*
X32736Y291389D01*
X32795Y291436D01*
X32818Y291448D01*
X32724D01*
X32666D01*
X32630D01*
X32619D01*
X32384Y291436D01*
X32161Y291424D01*
X31962Y291401D01*
X31774Y291377D01*
X31621Y291342D01*
X31504Y291318D01*
X31457Y291307D01*
X31422D01*
X31410Y291295D01*
X31398D01*
X31187Y291236D01*
X30999Y291178D01*
X30835Y291119D01*
X30694Y291060D01*
X30589Y291013D01*
X30506Y290966D01*
X30448Y290943D01*
X30436Y290931D01*
X30307Y290837D01*
X30201Y290743D01*
X30107Y290650D01*
X30025Y290556D01*
X29955Y290485D01*
X29908Y290415D01*
X29884Y290368D01*
X29873Y290356D01*
X29802Y290227D01*
X29755Y290086D01*
X29720Y289957D01*
X29697Y289828D01*
X29685Y289722D01*
X29673Y289640D01*
Y289558D01*
X29685Y289370D01*
X29720Y289194D01*
X29767Y289042D01*
X29826Y288913D01*
X29873Y288819D01*
X29920Y288737D01*
X29955Y288690D01*
X29966Y288678D01*
X30096Y288561D01*
X30248Y288467D01*
X30412Y288385D01*
X30577Y288326D01*
X30718Y288279D01*
X30847Y288244D01*
X30894Y288232D01*
X30917D01*
X30940Y288220D01*
X30952D01*
X30870Y287258D01*
X30530Y287329D01*
X30236Y287422D01*
X29978Y287540D01*
X29767Y287657D01*
X29603Y287775D01*
X29532Y287833D01*
X29474Y287880D01*
X29439Y287915D01*
X29403Y287950D01*
X29392Y287962D01*
X29380Y287974D01*
X29286Y288091D01*
X29204Y288220D01*
X29075Y288479D01*
X28981Y288737D01*
X28922Y288983D01*
X28875Y289206D01*
X28863Y289300D01*
Y289382D01*
X28852Y289441D01*
Y289535D01*
X28875Y289863D01*
X28922Y290157D01*
X29004Y290427D01*
X29098Y290650D01*
X29133Y290743D01*
X29180Y290837D01*
X29227Y290908D01*
X29262Y290978D01*
X29286Y291025D01*
X29309Y291060D01*
X29333Y291084D01*
Y291095D01*
X29532Y291330D01*
X29755Y291541D01*
X29990Y291706D01*
X30213Y291847D01*
X30412Y291964D01*
X30506Y292011D01*
X30577Y292046D01*
X30647Y292069D01*
X30694Y292093D01*
X30718Y292105D01*
X30729D01*
X30905Y292163D01*
X31105Y292222D01*
X31504Y292304D01*
X31926Y292363D01*
X32325Y292398D01*
X32501Y292421D01*
X32677Y292433D01*
X32830D01*
X32959Y292445D01*
X33064D01*
X33147D01*
X33205D01*
X33217D01*
X33487D01*
X33745Y292433D01*
D02*
G37*
G36*
X37148Y283902D02*
X36949Y283785D01*
X36761Y283656D01*
X36573Y283503D01*
X36409Y283362D01*
X36268Y283221D01*
X36151Y283116D01*
X36116Y283069D01*
X36080Y283034D01*
X36069Y283022D01*
X36057Y283010D01*
X35857Y282764D01*
X35670Y282517D01*
X35505Y282283D01*
X35376Y282048D01*
X35259Y281848D01*
X35212Y281766D01*
X35177Y281696D01*
X35142Y281637D01*
X35130Y281590D01*
X35106Y281567D01*
Y281555D01*
X34144D01*
X34214Y281731D01*
X34297Y281907D01*
X34379Y282083D01*
X34461Y282247D01*
X34531Y282388D01*
X34590Y282506D01*
X34637Y282576D01*
X34649Y282588D01*
Y282599D01*
X34778Y282811D01*
X34907Y282998D01*
X35024Y283163D01*
X35130Y283292D01*
X35212Y283409D01*
X35282Y283479D01*
X35329Y283538D01*
X35341Y283550D01*
X28993D01*
Y284547D01*
X37148D01*
Y283902D01*
D02*
G37*
G36*
X75428Y292867D02*
X75616D01*
X75804Y292856D01*
X75968Y292832D01*
X76132Y292820D01*
X76273Y292809D01*
X76402Y292785D01*
X76520Y292773D01*
X76625Y292750D01*
X76707Y292738D01*
X76778Y292727D01*
X76837Y292715D01*
X76872Y292703D01*
X76895Y292691D01*
X76907D01*
X77165Y292621D01*
X77400Y292539D01*
X77599Y292445D01*
X77775Y292374D01*
X77928Y292292D01*
X78033Y292245D01*
X78092Y292199D01*
X78116Y292187D01*
X78292Y292058D01*
X78444Y291929D01*
X78573Y291788D01*
X78691Y291659D01*
X78773Y291541D01*
X78831Y291448D01*
X78867Y291389D01*
X78878Y291377D01*
Y291365D01*
X78972Y291178D01*
X79031Y290978D01*
X79078Y290790D01*
X79113Y290614D01*
X79137Y290462D01*
X79148Y290333D01*
Y290227D01*
X79125Y289910D01*
X79078Y289617D01*
X78996Y289370D01*
X78914Y289159D01*
X78820Y288983D01*
X78784Y288913D01*
X78738Y288854D01*
X78714Y288807D01*
X78691Y288772D01*
X78667Y288760D01*
Y288748D01*
X78479Y288537D01*
X78256Y288361D01*
X78033Y288209D01*
X77822Y288091D01*
X77623Y287997D01*
X77541Y287950D01*
X77458Y287927D01*
X77400Y287904D01*
X77353Y287880D01*
X77329Y287868D01*
X77318D01*
X77142Y287821D01*
X76966Y287775D01*
X76578Y287704D01*
X76191Y287645D01*
X75827Y287610D01*
X75651Y287598D01*
X75499Y287587D01*
X75358D01*
X75229Y287575D01*
X75135D01*
X75053D01*
X75006D01*
X74994D01*
X74583Y287587D01*
X74196Y287610D01*
X73844Y287645D01*
X73516Y287704D01*
X73210Y287763D01*
X72941Y287833D01*
X72694Y287904D01*
X72483Y287974D01*
X72295Y288044D01*
X72131Y288127D01*
X71990Y288185D01*
X71884Y288244D01*
X71790Y288302D01*
X71732Y288338D01*
X71697Y288361D01*
X71685Y288373D01*
X71544Y288502D01*
X71415Y288643D01*
X71298Y288795D01*
X71204Y288948D01*
X71122Y289100D01*
X71051Y289253D01*
X71004Y289406D01*
X70957Y289546D01*
X70922Y289687D01*
X70899Y289816D01*
X70875Y289934D01*
X70863Y290028D01*
X70852Y290110D01*
Y290227D01*
X70875Y290544D01*
X70922Y290837D01*
X71004Y291084D01*
X71086Y291295D01*
X71169Y291471D01*
X71216Y291530D01*
X71251Y291588D01*
X71274Y291635D01*
X71298Y291670D01*
X71321Y291682D01*
Y291694D01*
X71521Y291905D01*
X71732Y292081D01*
X71967Y292234D01*
X72178Y292351D01*
X72377Y292445D01*
X72459Y292492D01*
X72542Y292515D01*
X72600Y292539D01*
X72647Y292562D01*
X72671Y292574D01*
X72682D01*
X72858Y292633D01*
X73034Y292680D01*
X73410Y292750D01*
X73797Y292809D01*
X74173Y292844D01*
X74337Y292856D01*
X74489Y292867D01*
X74630D01*
X74759Y292879D01*
X74853D01*
X74935D01*
X74982D01*
X74994D01*
X75217D01*
X75428Y292867D01*
D02*
G37*
G36*
X71955Y282506D02*
X72154Y282646D01*
X72236Y282717D01*
X72319Y282775D01*
X72389Y282834D01*
X72436Y282881D01*
X72471Y282916D01*
X72483Y282928D01*
X72542Y282987D01*
X72600Y283057D01*
X72753Y283221D01*
X72929Y283409D01*
X73105Y283609D01*
X73257Y283796D01*
X73328Y283878D01*
X73398Y283949D01*
X73445Y284008D01*
X73480Y284055D01*
X73504Y284078D01*
X73516Y284090D01*
X73680Y284277D01*
X73832Y284465D01*
X73985Y284630D01*
X74114Y284782D01*
X74243Y284923D01*
X74360Y285040D01*
X74466Y285158D01*
X74560Y285252D01*
X74654Y285345D01*
X74724Y285416D01*
X74783Y285474D01*
X74842Y285533D01*
X74912Y285592D01*
X74935Y285615D01*
X75135Y285780D01*
X75311Y285920D01*
X75487Y286038D01*
X75628Y286132D01*
X75757Y286202D01*
X75851Y286249D01*
X75909Y286272D01*
X75933Y286284D01*
X76109Y286355D01*
X76285Y286402D01*
X76449Y286448D01*
X76590Y286472D01*
X76719Y286484D01*
X76813Y286495D01*
X76872D01*
X76895D01*
X77071Y286484D01*
X77235Y286460D01*
X77400Y286437D01*
X77541Y286390D01*
X77822Y286272D01*
X78045Y286155D01*
X78151Y286085D01*
X78233Y286026D01*
X78315Y285967D01*
X78374Y285909D01*
X78421Y285862D01*
X78468Y285838D01*
X78479Y285815D01*
X78491Y285803D01*
X78608Y285674D01*
X78714Y285533D01*
X78796Y285381D01*
X78867Y285228D01*
X78984Y284923D01*
X79066Y284618D01*
X79090Y284489D01*
X79113Y284360D01*
X79125Y284242D01*
X79137Y284148D01*
X79148Y284066D01*
Y283949D01*
X79137Y283738D01*
X79125Y283538D01*
X79090Y283351D01*
X79054Y283174D01*
X79007Y283010D01*
X78960Y282858D01*
X78902Y282717D01*
X78843Y282588D01*
X78784Y282470D01*
X78726Y282376D01*
X78679Y282294D01*
X78632Y282224D01*
X78597Y282165D01*
X78562Y282130D01*
X78550Y282107D01*
X78538Y282095D01*
X78421Y281978D01*
X78292Y281872D01*
X78151Y281766D01*
X78010Y281684D01*
X77728Y281543D01*
X77447Y281449D01*
X77318Y281414D01*
X77189Y281379D01*
X77083Y281355D01*
X76989Y281332D01*
X76907Y281320D01*
X76848D01*
X76813Y281309D01*
X76801D01*
X76696Y282330D01*
X76966Y282353D01*
X77200Y282400D01*
X77411Y282470D01*
X77576Y282553D01*
X77717Y282623D01*
X77811Y282693D01*
X77869Y282740D01*
X77893Y282764D01*
X78033Y282940D01*
X78139Y283127D01*
X78221Y283327D01*
X78268Y283503D01*
X78303Y283667D01*
X78315Y283808D01*
X78327Y283855D01*
Y283925D01*
X78315Y284172D01*
X78268Y284395D01*
X78198Y284583D01*
X78127Y284747D01*
X78045Y284876D01*
X77986Y284958D01*
X77940Y285017D01*
X77916Y285040D01*
X77752Y285181D01*
X77587Y285287D01*
X77423Y285369D01*
X77259Y285416D01*
X77130Y285451D01*
X77013Y285463D01*
X76942Y285474D01*
X76930D01*
X76919D01*
X76707Y285451D01*
X76484Y285404D01*
X76285Y285322D01*
X76097Y285240D01*
X75945Y285146D01*
X75816Y285064D01*
X75769Y285040D01*
X75733Y285017D01*
X75722Y284993D01*
X75710D01*
X75581Y284900D01*
X75452Y284782D01*
X75311Y284653D01*
X75170Y284512D01*
X74889Y284219D01*
X74607Y283925D01*
X74478Y283773D01*
X74360Y283644D01*
X74255Y283515D01*
X74161Y283409D01*
X74091Y283327D01*
X74032Y283257D01*
X73997Y283210D01*
X73985Y283198D01*
X73738Y282904D01*
X73504Y282635D01*
X73293Y282412D01*
X73117Y282236D01*
X72964Y282083D01*
X72858Y281978D01*
X72788Y281919D01*
X72776Y281895D01*
X72765D01*
X72565Y281731D01*
X72377Y281602D01*
X72189Y281485D01*
X72025Y281391D01*
X71884Y281320D01*
X71779Y281273D01*
X71708Y281250D01*
X71697Y281238D01*
X71685D01*
X71556Y281191D01*
X71438Y281168D01*
X71321Y281144D01*
X71216Y281133D01*
X71122Y281121D01*
X71051D01*
X71004D01*
X70993D01*
Y286507D01*
X71955D01*
Y282506D01*
D02*
G37*
G36*
X71884Y218692D02*
X72084Y218832D01*
X72166Y218903D01*
X72248Y218962D01*
X72319Y219020D01*
X72366Y219067D01*
X72401Y219102D01*
X72413Y219114D01*
X72471Y219173D01*
X72530Y219243D01*
X72682Y219407D01*
X72858Y219595D01*
X73034Y219795D01*
X73187Y219982D01*
X73257Y220065D01*
X73328Y220135D01*
X73375Y220194D01*
X73410Y220241D01*
X73433Y220264D01*
X73445Y220276D01*
X73609Y220464D01*
X73762Y220651D01*
X73915Y220816D01*
X74044Y220968D01*
X74173Y221109D01*
X74290Y221226D01*
X74396Y221344D01*
X74490Y221437D01*
X74583Y221531D01*
X74654Y221602D01*
X74713Y221660D01*
X74771Y221719D01*
X74842Y221778D01*
X74865Y221801D01*
X75065Y221966D01*
X75241Y222106D01*
X75417Y222224D01*
X75557Y222318D01*
X75686Y222388D01*
X75780Y222435D01*
X75839Y222458D01*
X75862Y222470D01*
X76039Y222541D01*
X76215Y222588D01*
X76379Y222635D01*
X76520Y222658D01*
X76649Y222670D01*
X76743Y222681D01*
X76801D01*
X76825D01*
X77001Y222670D01*
X77165Y222646D01*
X77329Y222623D01*
X77470Y222576D01*
X77752Y222458D01*
X77975Y222341D01*
X78080Y222271D01*
X78163Y222212D01*
X78245Y222153D01*
X78303Y222095D01*
X78350Y222048D01*
X78397Y222024D01*
X78409Y222001D01*
X78421Y221989D01*
X78538Y221860D01*
X78644Y221719D01*
X78726Y221567D01*
X78796Y221414D01*
X78914Y221109D01*
X78996Y220804D01*
X79019Y220675D01*
X79043Y220546D01*
X79054Y220428D01*
X79066Y220334D01*
X79078Y220252D01*
Y220135D01*
X79066Y219924D01*
X79054Y219724D01*
X79019Y219536D01*
X78984Y219360D01*
X78937Y219196D01*
X78890Y219044D01*
X78831Y218903D01*
X78773Y218774D01*
X78714Y218656D01*
X78655Y218563D01*
X78608Y218480D01*
X78562Y218410D01*
X78526Y218351D01*
X78491Y218316D01*
X78479Y218293D01*
X78468Y218281D01*
X78350Y218164D01*
X78221Y218058D01*
X78080Y217952D01*
X77940Y217870D01*
X77658Y217729D01*
X77376Y217635D01*
X77247Y217600D01*
X77118Y217565D01*
X77013Y217542D01*
X76919Y217518D01*
X76837Y217506D01*
X76778D01*
X76743Y217495D01*
X76731D01*
X76625Y218515D01*
X76895Y218539D01*
X77130Y218586D01*
X77341Y218656D01*
X77505Y218738D01*
X77646Y218809D01*
X77740Y218879D01*
X77799Y218926D01*
X77822Y218950D01*
X77963Y219126D01*
X78069Y219314D01*
X78151Y219513D01*
X78198Y219689D01*
X78233Y219853D01*
X78245Y219994D01*
X78256Y220041D01*
Y220112D01*
X78245Y220358D01*
X78198Y220581D01*
X78127Y220769D01*
X78057Y220933D01*
X77975Y221062D01*
X77916Y221144D01*
X77869Y221203D01*
X77846Y221226D01*
X77681Y221367D01*
X77517Y221473D01*
X77353Y221555D01*
X77189Y221602D01*
X77059Y221637D01*
X76942Y221649D01*
X76872Y221660D01*
X76860D01*
X76848D01*
X76637Y221637D01*
X76414Y221590D01*
X76215Y221508D01*
X76027Y221426D01*
X75874Y221332D01*
X75745Y221250D01*
X75698Y221226D01*
X75663Y221203D01*
X75651Y221179D01*
X75640D01*
X75511Y221085D01*
X75381Y220968D01*
X75241Y220839D01*
X75100Y220698D01*
X74818Y220405D01*
X74536Y220112D01*
X74407Y219959D01*
X74290Y219830D01*
X74184Y219701D01*
X74091Y219595D01*
X74020Y219513D01*
X73962Y219443D01*
X73926Y219396D01*
X73915Y219384D01*
X73668Y219090D01*
X73433Y218821D01*
X73222Y218598D01*
X73046Y218422D01*
X72894Y218269D01*
X72788Y218164D01*
X72718Y218105D01*
X72706Y218081D01*
X72694D01*
X72495Y217917D01*
X72307Y217788D01*
X72119Y217671D01*
X71955Y217577D01*
X71814Y217506D01*
X71708Y217459D01*
X71638Y217436D01*
X71626Y217424D01*
X71614D01*
X71486Y217377D01*
X71368Y217354D01*
X71251Y217330D01*
X71145Y217319D01*
X71051Y217307D01*
X70981D01*
X70934D01*
X70922D01*
Y222693D01*
X71884D01*
Y218692D01*
D02*
G37*
G36*
X37078Y220851D02*
X36878Y220733D01*
X36691Y220604D01*
X36503Y220452D01*
X36339Y220311D01*
X36198Y220170D01*
X36080Y220065D01*
X36045Y220018D01*
X36010Y219982D01*
X35998Y219971D01*
X35986Y219959D01*
X35787Y219713D01*
X35599Y219466D01*
X35435Y219231D01*
X35306Y218997D01*
X35189Y218797D01*
X35142Y218715D01*
X35106Y218645D01*
X35071Y218586D01*
X35059Y218539D01*
X35036Y218515D01*
Y218504D01*
X34074D01*
X34144Y218680D01*
X34226Y218856D01*
X34308Y219032D01*
X34391Y219196D01*
X34461Y219337D01*
X34520Y219454D01*
X34567Y219525D01*
X34578Y219536D01*
Y219548D01*
X34707Y219759D01*
X34836Y219947D01*
X34954Y220112D01*
X35059Y220241D01*
X35142Y220358D01*
X35212Y220428D01*
X35259Y220487D01*
X35271Y220499D01*
X28922D01*
Y221496D01*
X37078D01*
Y220851D01*
D02*
G37*
G36*
X106925Y125238D02*
X107077Y125016D01*
X107258Y124794D01*
X107424Y124600D01*
X107590Y124434D01*
X107715Y124295D01*
X107771Y124253D01*
X107812Y124212D01*
X107826Y124198D01*
X107840Y124184D01*
X108131Y123948D01*
X108422Y123726D01*
X108700Y123532D01*
X108977Y123380D01*
X109213Y123241D01*
X109310Y123186D01*
X109393Y123144D01*
X109463Y123102D01*
X109518Y123089D01*
X109546Y123061D01*
X109560D01*
Y121924D01*
X109352Y122007D01*
X109144Y122104D01*
X108936Y122201D01*
X108742Y122298D01*
X108575Y122381D01*
X108436Y122451D01*
X108353Y122506D01*
X108339Y122520D01*
X108325D01*
X108076Y122672D01*
X107854Y122825D01*
X107660Y122964D01*
X107507Y123089D01*
X107368Y123186D01*
X107285Y123269D01*
X107216Y123324D01*
X107202Y123338D01*
Y115835D01*
X106023D01*
Y125474D01*
X106786D01*
X106925Y125238D01*
D02*
G37*
G36*
X118921Y115835D02*
X117645D01*
Y119732D01*
X115190D01*
X114830Y119746D01*
X114483Y119774D01*
X114178Y119816D01*
X113900Y119871D01*
X113637Y119927D01*
X113415Y119996D01*
X113207Y120079D01*
X113027Y120162D01*
X112874Y120232D01*
X112736Y120315D01*
X112625Y120384D01*
X112541Y120454D01*
X112472Y120495D01*
X112430Y120537D01*
X112403Y120564D01*
X112389Y120578D01*
X112250Y120745D01*
X112125Y120911D01*
X112028Y121077D01*
X111931Y121258D01*
X111848Y121438D01*
X111792Y121604D01*
X111695Y121924D01*
X111668Y122076D01*
X111640Y122215D01*
X111626Y122340D01*
X111612Y122437D01*
X111598Y122534D01*
Y122589D01*
Y122631D01*
Y122645D01*
X111612Y122908D01*
X111640Y123158D01*
X111695Y123380D01*
X111737Y123574D01*
X111792Y123740D01*
X111848Y123865D01*
X111876Y123934D01*
X111890Y123962D01*
X112001Y124170D01*
X112139Y124351D01*
X112264Y124517D01*
X112389Y124642D01*
X112500Y124739D01*
X112583Y124822D01*
X112639Y124864D01*
X112666Y124878D01*
X112846Y124988D01*
X113055Y125085D01*
X113249Y125169D01*
X113429Y125238D01*
X113595Y125280D01*
X113720Y125307D01*
X113817Y125335D01*
X113845D01*
X114053Y125363D01*
X114289Y125391D01*
X114538Y125405D01*
X114774Y125418D01*
X114982Y125432D01*
X118921D01*
Y115835D01*
D02*
G37*
G36*
X103402Y119219D02*
Y118137D01*
X99228D01*
Y115835D01*
X98049D01*
Y118137D01*
X96745D01*
Y119219D01*
X98049D01*
Y125432D01*
X99006D01*
X103402Y119219D01*
D02*
G37*
G36*
X132926Y464595D02*
X133231Y464539D01*
X133495Y464456D01*
X133716Y464373D01*
X133897Y464290D01*
X134035Y464206D01*
X134119Y464151D01*
X134146Y464137D01*
X134354Y463943D01*
X134535Y463735D01*
X134673Y463513D01*
X134784Y463291D01*
X134867Y463097D01*
X134923Y462944D01*
X134937Y462889D01*
X134951Y462847D01*
X134965Y462820D01*
Y462806D01*
X135089Y463041D01*
X135214Y463236D01*
X135353Y463402D01*
X135478Y463541D01*
X135589Y463652D01*
X135686Y463735D01*
X135741Y463776D01*
X135769Y463790D01*
X135963Y463901D01*
X136157Y463984D01*
X136351Y464054D01*
X136532Y464095D01*
X136684Y464123D01*
X136795Y464137D01*
X136878D01*
X136906D01*
X137142Y464123D01*
X137378Y464081D01*
X137586Y464026D01*
X137766Y463957D01*
X137919Y463887D01*
X138043Y463832D01*
X138113Y463790D01*
X138140Y463776D01*
X138349Y463638D01*
X138529Y463471D01*
X138681Y463305D01*
X138820Y463139D01*
X138917Y463000D01*
X139000Y462875D01*
X139042Y462792D01*
X139056Y462778D01*
Y462764D01*
X139167Y462514D01*
X139250Y462265D01*
X139319Y462015D01*
X139361Y461793D01*
X139389Y461613D01*
X139403Y461460D01*
Y461114D01*
X139375Y460920D01*
X139305Y460545D01*
X139194Y460226D01*
X139083Y459949D01*
X139014Y459824D01*
X138959Y459727D01*
X138903Y459630D01*
X138848Y459560D01*
X138806Y459505D01*
X138778Y459463D01*
X138764Y459436D01*
X138751Y459422D01*
X138487Y459158D01*
X138196Y458950D01*
X137891Y458784D01*
X137586Y458645D01*
X137322Y458562D01*
X137211Y458520D01*
X137114Y458493D01*
X137031Y458479D01*
X136975Y458465D01*
X136934Y458451D01*
X136920D01*
X136712Y459630D01*
X137017Y459685D01*
X137281Y459768D01*
X137502Y459866D01*
X137683Y459963D01*
X137822Y460060D01*
X137919Y460143D01*
X137988Y460198D01*
X138002Y460212D01*
X138140Y460393D01*
X138251Y460587D01*
X138321Y460767D01*
X138376Y460947D01*
X138404Y461114D01*
X138432Y461239D01*
Y461349D01*
X138418Y461599D01*
X138362Y461821D01*
X138293Y462015D01*
X138224Y462182D01*
X138140Y462306D01*
X138071Y462403D01*
X138016Y462473D01*
X138002Y462487D01*
X137835Y462639D01*
X137655Y462750D01*
X137475Y462820D01*
X137308Y462875D01*
X137156Y462903D01*
X137045Y462930D01*
X136962D01*
X136948D01*
X136934D01*
X136781D01*
X136643Y462903D01*
X136407Y462833D01*
X136199Y462736D01*
X136019Y462625D01*
X135894Y462514D01*
X135797Y462417D01*
X135741Y462348D01*
X135727Y462334D01*
Y462320D01*
X135603Y462085D01*
X135506Y461863D01*
X135436Y461627D01*
X135394Y461419D01*
X135367Y461239D01*
X135339Y461086D01*
Y460906D01*
X135353Y460850D01*
Y460781D01*
X134313Y460642D01*
X134354Y460822D01*
X134382Y460989D01*
X134410Y461128D01*
X134424Y461252D01*
X134438Y461349D01*
Y461474D01*
X134410Y461766D01*
X134354Y462029D01*
X134271Y462265D01*
X134174Y462459D01*
X134077Y462612D01*
X133994Y462722D01*
X133938Y462792D01*
X133911Y462820D01*
X133703Y463000D01*
X133481Y463139D01*
X133259Y463236D01*
X133037Y463291D01*
X132857Y463333D01*
X132704Y463346D01*
X132649Y463360D01*
X132607D01*
X132579D01*
X132565D01*
X132260Y463333D01*
X131983Y463263D01*
X131747Y463180D01*
X131539Y463069D01*
X131373Y462958D01*
X131248Y462875D01*
X131165Y462806D01*
X131137Y462778D01*
X130943Y462556D01*
X130804Y462320D01*
X130707Y462085D01*
X130638Y461863D01*
X130596Y461668D01*
X130582Y461516D01*
X130568Y461460D01*
Y461377D01*
X130582Y461128D01*
X130638Y460892D01*
X130707Y460684D01*
X130790Y460517D01*
X130860Y460379D01*
X130929Y460268D01*
X130984Y460212D01*
X130998Y460185D01*
X131192Y460018D01*
X131414Y459879D01*
X131650Y459755D01*
X131900Y459658D01*
X132108Y459588D01*
X132205Y459560D01*
X132288Y459547D01*
X132357Y459533D01*
X132413Y459519D01*
X132441Y459505D01*
X132454D01*
X132302Y458326D01*
X132080Y458354D01*
X131872Y458396D01*
X131484Y458520D01*
X131151Y458673D01*
X131012Y458756D01*
X130873Y458839D01*
X130749Y458923D01*
X130652Y459006D01*
X130555Y459075D01*
X130485Y459144D01*
X130430Y459186D01*
X130388Y459228D01*
X130360Y459255D01*
X130346Y459269D01*
X130222Y459436D01*
X130097Y459602D01*
X130000Y459768D01*
X129916Y459949D01*
X129778Y460295D01*
X129695Y460628D01*
X129667Y460781D01*
X129639Y460920D01*
X129625Y461044D01*
X129611Y461155D01*
X129598Y461239D01*
Y461363D01*
X129611Y461627D01*
X129639Y461863D01*
X129681Y462098D01*
X129736Y462320D01*
X129806Y462528D01*
X129875Y462709D01*
X129958Y462889D01*
X130041Y463041D01*
X130111Y463194D01*
X130194Y463319D01*
X130263Y463430D01*
X130333Y463513D01*
X130388Y463582D01*
X130430Y463638D01*
X130457Y463666D01*
X130471Y463679D01*
X130638Y463846D01*
X130818Y463984D01*
X130998Y464109D01*
X131179Y464220D01*
X131345Y464303D01*
X131525Y464387D01*
X131858Y464498D01*
X132011Y464525D01*
X132149Y464553D01*
X132274Y464581D01*
X132385Y464595D01*
X132468Y464608D01*
X132538D01*
X132579D01*
X132593D01*
X132926Y464595D01*
D02*
G37*
G36*
X139403Y454526D02*
X139167Y454388D01*
X138945Y454235D01*
X138723Y454055D01*
X138529Y453888D01*
X138362Y453722D01*
X138224Y453597D01*
X138182Y453542D01*
X138140Y453500D01*
X138127Y453486D01*
X138113Y453472D01*
X137877Y453181D01*
X137655Y452890D01*
X137461Y452612D01*
X137308Y452335D01*
X137170Y452099D01*
X137114Y452002D01*
X137073Y451919D01*
X137031Y451850D01*
X137017Y451794D01*
X136989Y451766D01*
Y451753D01*
X135852D01*
X135935Y451961D01*
X136032Y452169D01*
X136130Y452377D01*
X136227Y452571D01*
X136310Y452737D01*
X136379Y452876D01*
X136435Y452959D01*
X136448Y452973D01*
Y452987D01*
X136601Y453237D01*
X136754Y453458D01*
X136892Y453652D01*
X137017Y453805D01*
X137114Y453944D01*
X137197Y454027D01*
X137253Y454096D01*
X137267Y454110D01*
X129764D01*
Y455289D01*
X139403D01*
Y454526D01*
D02*
G37*
G36*
X136837Y449700D02*
X137086Y449672D01*
X137308Y449617D01*
X137502Y449575D01*
X137669Y449520D01*
X137794Y449464D01*
X137863Y449436D01*
X137891Y449423D01*
X138099Y449312D01*
X138279Y449173D01*
X138446Y449048D01*
X138570Y448923D01*
X138667Y448812D01*
X138751Y448729D01*
X138792Y448674D01*
X138806Y448646D01*
X138917Y448466D01*
X139014Y448258D01*
X139097Y448064D01*
X139167Y447883D01*
X139208Y447717D01*
X139236Y447592D01*
X139264Y447495D01*
Y447467D01*
X139291Y447259D01*
X139319Y447023D01*
X139333Y446774D01*
X139347Y446538D01*
X139361Y446330D01*
Y442391D01*
X129764D01*
Y443667D01*
X133661D01*
Y446122D01*
X133675Y446483D01*
X133703Y446829D01*
X133744Y447134D01*
X133800Y447412D01*
X133855Y447675D01*
X133925Y447897D01*
X134008Y448105D01*
X134091Y448285D01*
X134160Y448438D01*
X134243Y448577D01*
X134313Y448688D01*
X134382Y448771D01*
X134424Y448840D01*
X134465Y448882D01*
X134493Y448909D01*
X134507Y448923D01*
X134673Y449062D01*
X134840Y449187D01*
X135006Y449284D01*
X135187Y449381D01*
X135367Y449464D01*
X135533Y449520D01*
X135852Y449617D01*
X136005Y449645D01*
X136143Y449672D01*
X136268Y449686D01*
X136365Y449700D01*
X136462Y449714D01*
X136518D01*
X136559D01*
X136573D01*
X136837Y449700D01*
D02*
G37*
G36*
X355362Y476417D02*
X355515Y476195D01*
X355695Y475973D01*
X355862Y475779D01*
X356028Y475612D01*
X356153Y475474D01*
X356208Y475432D01*
X356250Y475391D01*
X356264Y475377D01*
X356278Y475363D01*
X356569Y475127D01*
X356860Y474905D01*
X357138Y474711D01*
X357415Y474558D01*
X357651Y474420D01*
X357748Y474364D01*
X357831Y474323D01*
X357900Y474281D01*
X357956Y474267D01*
X357984Y474239D01*
X357997D01*
Y473102D01*
X357789Y473185D01*
X357581Y473283D01*
X357373Y473380D01*
X357179Y473477D01*
X357013Y473560D01*
X356874Y473629D01*
X356791Y473685D01*
X356777Y473699D01*
X356763D01*
X356513Y473851D01*
X356292Y474004D01*
X356097Y474142D01*
X355945Y474267D01*
X355806Y474364D01*
X355723Y474447D01*
X355654Y474503D01*
X355640Y474517D01*
Y467014D01*
X354461D01*
Y476652D01*
X355224D01*
X355362Y476417D01*
D02*
G37*
G36*
X348317Y476639D02*
X348581Y476611D01*
X348830Y476555D01*
X349066Y476486D01*
X349274Y476389D01*
X349482Y476306D01*
X349663Y476195D01*
X349829Y476098D01*
X349968Y476001D01*
X350106Y475890D01*
X350217Y475807D01*
X350300Y475723D01*
X350370Y475640D01*
X350425Y475585D01*
X350453Y475557D01*
X350467Y475543D01*
X350647Y475293D01*
X350800Y475002D01*
X350938Y474697D01*
X351063Y474378D01*
X351160Y474045D01*
X351244Y473712D01*
X351313Y473366D01*
X351368Y473047D01*
X351410Y472728D01*
X351438Y472436D01*
X351465Y472173D01*
X351479Y471951D01*
Y471757D01*
X351493Y471618D01*
Y471563D01*
Y471521D01*
Y471507D01*
Y471493D01*
X351479Y471050D01*
X351451Y470634D01*
X351410Y470245D01*
X351341Y469885D01*
X351271Y469566D01*
X351202Y469274D01*
X351119Y469011D01*
X351022Y468775D01*
X350938Y468581D01*
X350855Y468401D01*
X350786Y468262D01*
X350703Y468137D01*
X350647Y468040D01*
X350606Y467985D01*
X350578Y467943D01*
X350564Y467929D01*
X350384Y467735D01*
X350190Y467569D01*
X349995Y467430D01*
X349801Y467305D01*
X349593Y467194D01*
X349399Y467111D01*
X349205Y467042D01*
X349011Y466986D01*
X348844Y466945D01*
X348678Y466903D01*
X348539Y466875D01*
X348414Y466861D01*
X348303D01*
X348234Y466847D01*
X348165D01*
X347846Y466861D01*
X347555Y466917D01*
X347291Y466972D01*
X347055Y467056D01*
X346875Y467125D01*
X346736Y467194D01*
X346681Y467208D01*
X346639Y467236D01*
X346625Y467250D01*
X346612D01*
X346376Y467416D01*
X346154Y467610D01*
X345974Y467804D01*
X345821Y467999D01*
X345696Y468179D01*
X345613Y468318D01*
X345585Y468373D01*
X345558Y468415D01*
X345544Y468428D01*
Y468442D01*
X345405Y468734D01*
X345308Y469039D01*
X345238Y469316D01*
X345197Y469580D01*
X345155Y469801D01*
Y469885D01*
X345141Y469968D01*
Y470037D01*
Y470079D01*
Y470107D01*
Y470121D01*
X345155Y470370D01*
X345183Y470606D01*
X345225Y470842D01*
X345266Y471050D01*
X345336Y471244D01*
X345405Y471438D01*
X345474Y471604D01*
X345558Y471757D01*
X345641Y471896D01*
X345710Y472020D01*
X345779Y472118D01*
X345849Y472215D01*
X345890Y472284D01*
X345932Y472326D01*
X345960Y472353D01*
X345974Y472367D01*
X346126Y472520D01*
X346292Y472658D01*
X346473Y472769D01*
X346639Y472866D01*
X346806Y472963D01*
X346972Y473033D01*
X347291Y473130D01*
X347430Y473172D01*
X347568Y473199D01*
X347679Y473213D01*
X347790Y473227D01*
X347873Y473241D01*
X347984D01*
X348234Y473227D01*
X348470Y473185D01*
X348692Y473144D01*
X348886Y473088D01*
X349052Y473019D01*
X349177Y472977D01*
X349260Y472936D01*
X349274Y472922D01*
X349288D01*
X349510Y472783D01*
X349704Y472631D01*
X349884Y472478D01*
X350023Y472312D01*
X350148Y472173D01*
X350245Y472062D01*
X350300Y471979D01*
X350314Y471965D01*
Y472215D01*
X350300Y472464D01*
X350287Y472686D01*
X350259Y472908D01*
X350245Y473102D01*
X350217Y473283D01*
X350190Y473449D01*
X350148Y473601D01*
X350120Y473740D01*
X350092Y473851D01*
X350065Y473948D01*
X350051Y474031D01*
X350023Y474087D01*
X350009Y474128D01*
X349995Y474156D01*
Y474170D01*
X349857Y474447D01*
X349718Y474697D01*
X349565Y474891D01*
X349427Y475058D01*
X349302Y475196D01*
X349205Y475293D01*
X349136Y475349D01*
X349108Y475363D01*
X348941Y475474D01*
X348775Y475543D01*
X348609Y475598D01*
X348442Y475640D01*
X348317Y475668D01*
X348206Y475682D01*
X348109D01*
X347860Y475654D01*
X347624Y475598D01*
X347430Y475515D01*
X347249Y475432D01*
X347111Y475335D01*
X347014Y475252D01*
X346958Y475196D01*
X346930Y475169D01*
X346833Y475044D01*
X346736Y474891D01*
X346653Y474725D01*
X346598Y474558D01*
X346542Y474406D01*
X346501Y474281D01*
X346487Y474198D01*
X346473Y474184D01*
Y474170D01*
X345294Y474267D01*
X345377Y474655D01*
X345502Y475002D01*
X345641Y475307D01*
X345793Y475557D01*
X345946Y475751D01*
X346001Y475834D01*
X346071Y475904D01*
X346112Y475945D01*
X346154Y475987D01*
X346168Y476001D01*
X346182Y476015D01*
X346320Y476125D01*
X346473Y476223D01*
X346778Y476389D01*
X347083Y476500D01*
X347374Y476569D01*
X347638Y476625D01*
X347749Y476639D01*
X347846D01*
X347929Y476652D01*
X348040D01*
X348317Y476639D01*
D02*
G37*
G36*
X367359Y467014D02*
X366083D01*
Y470911D01*
X363628D01*
X363267Y470925D01*
X362921Y470953D01*
X362616Y470994D01*
X362338Y471050D01*
X362075Y471105D01*
X361853Y471175D01*
X361645Y471258D01*
X361465Y471341D01*
X361312Y471410D01*
X361173Y471493D01*
X361062Y471563D01*
X360979Y471632D01*
X360910Y471674D01*
X360868Y471715D01*
X360840Y471743D01*
X360827Y471757D01*
X360688Y471923D01*
X360563Y472090D01*
X360466Y472256D01*
X360369Y472436D01*
X360286Y472617D01*
X360230Y472783D01*
X360133Y473102D01*
X360105Y473255D01*
X360078Y473393D01*
X360064Y473518D01*
X360050Y473615D01*
X360036Y473712D01*
Y473768D01*
Y473810D01*
Y473823D01*
X360050Y474087D01*
X360078Y474337D01*
X360133Y474558D01*
X360175Y474753D01*
X360230Y474919D01*
X360286Y475044D01*
X360313Y475113D01*
X360327Y475141D01*
X360438Y475349D01*
X360577Y475529D01*
X360702Y475696D01*
X360827Y475820D01*
X360938Y475918D01*
X361021Y476001D01*
X361076Y476042D01*
X361104Y476056D01*
X361284Y476167D01*
X361492Y476264D01*
X361686Y476347D01*
X361867Y476417D01*
X362033Y476458D01*
X362158Y476486D01*
X362255Y476514D01*
X362283D01*
X362491Y476541D01*
X362727Y476569D01*
X362976Y476583D01*
X363212Y476597D01*
X363420Y476611D01*
X367359D01*
Y467014D01*
D02*
G37*
G36*
X417980Y95321D02*
X418133Y95099D01*
X418313Y94878D01*
X418479Y94683D01*
X418646Y94517D01*
X418771Y94378D01*
X418826Y94337D01*
X418868Y94295D01*
X418882Y94281D01*
X418896Y94267D01*
X419187Y94031D01*
X419478Y93810D01*
X419755Y93615D01*
X420033Y93463D01*
X420269Y93324D01*
X420366Y93269D01*
X420449Y93227D01*
X420518Y93186D01*
X420574Y93172D01*
X420601Y93144D01*
X420615D01*
Y92007D01*
X420407Y92090D01*
X420199Y92187D01*
X419991Y92284D01*
X419797Y92381D01*
X419631Y92464D01*
X419492Y92534D01*
X419409Y92589D01*
X419395Y92603D01*
X419381D01*
X419131Y92756D01*
X418909Y92908D01*
X418715Y93047D01*
X418563Y93172D01*
X418424Y93269D01*
X418341Y93352D01*
X418271Y93407D01*
X418258Y93421D01*
Y85919D01*
X417079D01*
Y95557D01*
X417842D01*
X417980Y95321D01*
D02*
G37*
G36*
X413848Y90453D02*
X412738Y90301D01*
X412641Y90453D01*
X412516Y90578D01*
X412405Y90703D01*
X412294Y90800D01*
X412183Y90870D01*
X412100Y90939D01*
X412045Y90967D01*
X412031Y90980D01*
X411850Y91064D01*
X411670Y91133D01*
X411504Y91175D01*
X411337Y91216D01*
X411199Y91230D01*
X411088Y91244D01*
X410824D01*
X410658Y91216D01*
X410367Y91147D01*
X410117Y91050D01*
X409895Y90953D01*
X409729Y90842D01*
X409604Y90745D01*
X409534Y90675D01*
X409507Y90661D01*
Y90648D01*
X409313Y90412D01*
X409174Y90162D01*
X409077Y89899D01*
X409007Y89635D01*
X408966Y89413D01*
X408952Y89316D01*
Y89233D01*
X408938Y89164D01*
Y89108D01*
Y89080D01*
Y89067D01*
Y88872D01*
X408966Y88692D01*
X409035Y88345D01*
X409132Y88054D01*
X409229Y87818D01*
X409340Y87624D01*
X409437Y87472D01*
X409479Y87430D01*
X409507Y87388D01*
X409520Y87375D01*
X409534Y87361D01*
X409645Y87250D01*
X409756Y87153D01*
X410006Y86986D01*
X410242Y86875D01*
X410477Y86806D01*
X410672Y86751D01*
X410838Y86737D01*
X410894Y86723D01*
X410977D01*
X411240Y86737D01*
X411476Y86792D01*
X411684Y86861D01*
X411850Y86945D01*
X412003Y87028D01*
X412114Y87097D01*
X412169Y87153D01*
X412197Y87167D01*
X412364Y87361D01*
X412502Y87569D01*
X412613Y87805D01*
X412696Y88013D01*
X412752Y88221D01*
X412794Y88373D01*
X412807Y88442D01*
X412821Y88484D01*
Y88512D01*
Y88526D01*
X414055Y88429D01*
X414028Y88207D01*
X413986Y87999D01*
X413861Y87610D01*
X413709Y87278D01*
X413626Y87125D01*
X413542Y87000D01*
X413473Y86875D01*
X413390Y86764D01*
X413321Y86681D01*
X413251Y86612D01*
X413196Y86556D01*
X413168Y86501D01*
X413140Y86487D01*
X413126Y86473D01*
X412960Y86348D01*
X412794Y86237D01*
X412613Y86140D01*
X412433Y86057D01*
X412086Y85932D01*
X411740Y85849D01*
X411587Y85808D01*
X411434Y85794D01*
X411310Y85780D01*
X411199Y85766D01*
X411101Y85752D01*
X410977D01*
X410686Y85766D01*
X410408Y85808D01*
X410145Y85863D01*
X409909Y85932D01*
X409687Y86029D01*
X409479Y86126D01*
X409285Y86224D01*
X409118Y86334D01*
X408966Y86446D01*
X408827Y86543D01*
X408716Y86653D01*
X408619Y86737D01*
X408550Y86806D01*
X408494Y86861D01*
X408466Y86903D01*
X408453Y86917D01*
X408314Y87097D01*
X408203Y87291D01*
X408092Y87472D01*
X408009Y87666D01*
X407870Y88040D01*
X407787Y88401D01*
X407759Y88553D01*
X407732Y88706D01*
X407718Y88831D01*
X407704Y88942D01*
X407690Y89039D01*
Y89108D01*
Y89150D01*
Y89164D01*
X407704Y89413D01*
X407732Y89649D01*
X407773Y89885D01*
X407829Y90093D01*
X407898Y90287D01*
X407967Y90481D01*
X408050Y90648D01*
X408120Y90800D01*
X408203Y90939D01*
X408286Y91064D01*
X408356Y91161D01*
X408425Y91258D01*
X408480Y91327D01*
X408522Y91369D01*
X408550Y91397D01*
X408564Y91410D01*
X408730Y91563D01*
X408896Y91702D01*
X409077Y91812D01*
X409257Y91910D01*
X409437Y92007D01*
X409618Y92076D01*
X409950Y92173D01*
X410103Y92215D01*
X410242Y92242D01*
X410367Y92256D01*
X410477Y92270D01*
X410561Y92284D01*
X410866D01*
X411032Y92256D01*
X411365Y92187D01*
X411670Y92090D01*
X411948Y91979D01*
X412169Y91868D01*
X412267Y91812D01*
X412350Y91771D01*
X412419Y91729D01*
X412461Y91702D01*
X412488Y91688D01*
X412502Y91674D01*
X411989Y94267D01*
X408148D01*
Y95391D01*
X412918D01*
X413848Y90453D01*
D02*
G37*
G36*
X429976Y85919D02*
X428700D01*
Y89816D01*
X426246D01*
X425885Y89829D01*
X425538Y89857D01*
X425233Y89899D01*
X424956Y89954D01*
X424693Y90010D01*
X424471Y90079D01*
X424263Y90162D01*
X424082Y90245D01*
X423930Y90315D01*
X423791Y90398D01*
X423680Y90467D01*
X423597Y90537D01*
X423528Y90578D01*
X423486Y90620D01*
X423458Y90648D01*
X423444Y90661D01*
X423306Y90828D01*
X423181Y90994D01*
X423084Y91161D01*
X422987Y91341D01*
X422904Y91521D01*
X422848Y91688D01*
X422751Y92007D01*
X422723Y92159D01*
X422696Y92298D01*
X422682Y92423D01*
X422668Y92520D01*
X422654Y92617D01*
Y92672D01*
Y92714D01*
Y92728D01*
X422668Y92991D01*
X422696Y93241D01*
X422751Y93463D01*
X422793Y93657D01*
X422848Y93823D01*
X422904Y93948D01*
X422931Y94018D01*
X422945Y94045D01*
X423056Y94253D01*
X423195Y94434D01*
X423320Y94600D01*
X423444Y94725D01*
X423555Y94822D01*
X423639Y94905D01*
X423694Y94947D01*
X423722Y94961D01*
X423902Y95072D01*
X424110Y95169D01*
X424304Y95252D01*
X424484Y95321D01*
X424651Y95363D01*
X424776Y95391D01*
X424873Y95418D01*
X424901D01*
X425109Y95446D01*
X425344Y95474D01*
X425594Y95488D01*
X425830Y95501D01*
X426038Y95515D01*
X429976D01*
Y85919D01*
D02*
G37*
G36*
X181818Y460331D02*
X182054Y460497D01*
X182151Y460580D01*
X182248Y460650D01*
X182331Y460719D01*
X182387Y460775D01*
X182428Y460816D01*
X182442Y460830D01*
X182511Y460900D01*
X182581Y460983D01*
X182761Y461177D01*
X182969Y461399D01*
X183177Y461634D01*
X183357Y461856D01*
X183441Y461954D01*
X183524Y462037D01*
X183579Y462106D01*
X183621Y462161D01*
X183649Y462189D01*
X183662Y462203D01*
X183857Y462425D01*
X184037Y462647D01*
X184217Y462841D01*
X184370Y463021D01*
X184522Y463188D01*
X184661Y463326D01*
X184786Y463465D01*
X184897Y463576D01*
X185008Y463687D01*
X185091Y463770D01*
X185160Y463840D01*
X185230Y463909D01*
X185313Y463978D01*
X185340Y464006D01*
X185576Y464200D01*
X185784Y464367D01*
X185992Y464505D01*
X186159Y464616D01*
X186311Y464699D01*
X186422Y464755D01*
X186492Y464783D01*
X186519Y464796D01*
X186727Y464880D01*
X186935Y464935D01*
X187129Y464991D01*
X187296Y465018D01*
X187449Y465032D01*
X187560Y465046D01*
X187629D01*
X187656D01*
X187865Y465032D01*
X188059Y465005D01*
X188253Y464977D01*
X188419Y464921D01*
X188752Y464783D01*
X189016Y464644D01*
X189140Y464561D01*
X189237Y464491D01*
X189335Y464422D01*
X189404Y464353D01*
X189459Y464297D01*
X189515Y464269D01*
X189529Y464242D01*
X189543Y464228D01*
X189681Y464075D01*
X189806Y463909D01*
X189903Y463729D01*
X189986Y463548D01*
X190125Y463188D01*
X190222Y462827D01*
X190250Y462675D01*
X190278Y462522D01*
X190292Y462383D01*
X190305Y462272D01*
X190319Y462175D01*
Y462037D01*
X190305Y461787D01*
X190292Y461551D01*
X190250Y461329D01*
X190208Y461121D01*
X190153Y460927D01*
X190097Y460747D01*
X190028Y460580D01*
X189959Y460428D01*
X189889Y460289D01*
X189820Y460178D01*
X189764Y460081D01*
X189709Y459998D01*
X189667Y459929D01*
X189626Y459887D01*
X189612Y459859D01*
X189598Y459846D01*
X189459Y459707D01*
X189307Y459582D01*
X189140Y459457D01*
X188974Y459360D01*
X188641Y459194D01*
X188308Y459083D01*
X188156Y459041D01*
X188003Y458999D01*
X187878Y458972D01*
X187768Y458944D01*
X187670Y458930D01*
X187601D01*
X187560Y458916D01*
X187546D01*
X187421Y460123D01*
X187740Y460151D01*
X188017Y460206D01*
X188267Y460289D01*
X188461Y460386D01*
X188627Y460470D01*
X188738Y460553D01*
X188808Y460608D01*
X188835Y460636D01*
X189002Y460844D01*
X189127Y461066D01*
X189224Y461302D01*
X189279Y461510D01*
X189321Y461704D01*
X189335Y461870D01*
X189349Y461926D01*
Y462009D01*
X189335Y462300D01*
X189279Y462564D01*
X189196Y462786D01*
X189113Y462980D01*
X189016Y463132D01*
X188946Y463229D01*
X188891Y463299D01*
X188863Y463326D01*
X188669Y463493D01*
X188475Y463618D01*
X188281Y463715D01*
X188086Y463770D01*
X187934Y463812D01*
X187795Y463826D01*
X187712Y463840D01*
X187698D01*
X187684D01*
X187435Y463812D01*
X187171Y463756D01*
X186935Y463659D01*
X186714Y463562D01*
X186533Y463451D01*
X186381Y463354D01*
X186325Y463326D01*
X186284Y463299D01*
X186270Y463271D01*
X186256D01*
X186103Y463160D01*
X185951Y463021D01*
X185784Y462869D01*
X185618Y462702D01*
X185285Y462356D01*
X184952Y462009D01*
X184800Y461829D01*
X184661Y461676D01*
X184536Y461524D01*
X184425Y461399D01*
X184342Y461302D01*
X184273Y461218D01*
X184231Y461163D01*
X184217Y461149D01*
X183926Y460802D01*
X183649Y460483D01*
X183399Y460220D01*
X183191Y460012D01*
X183011Y459832D01*
X182886Y459707D01*
X182803Y459637D01*
X182789Y459610D01*
X182775D01*
X182539Y459416D01*
X182317Y459263D01*
X182095Y459124D01*
X181901Y459013D01*
X181735Y458930D01*
X181610Y458875D01*
X181527Y458847D01*
X181513Y458833D01*
X181499D01*
X181346Y458778D01*
X181208Y458750D01*
X181069Y458722D01*
X180944Y458708D01*
X180833Y458694D01*
X180750D01*
X180695D01*
X180681D01*
Y465060D01*
X181818D01*
Y460331D01*
D02*
G37*
G36*
X190319Y455075D02*
X190084Y454936D01*
X189862Y454784D01*
X189640Y454603D01*
X189446Y454437D01*
X189279Y454270D01*
X189140Y454146D01*
X189099Y454090D01*
X189057Y454049D01*
X189043Y454035D01*
X189030Y454021D01*
X188794Y453730D01*
X188572Y453438D01*
X188378Y453161D01*
X188225Y452883D01*
X188086Y452648D01*
X188031Y452551D01*
X187989Y452467D01*
X187948Y452398D01*
X187934Y452343D01*
X187906Y452315D01*
Y452301D01*
X186769D01*
X186852Y452509D01*
X186949Y452717D01*
X187046Y452925D01*
X187143Y453119D01*
X187227Y453286D01*
X187296Y453424D01*
X187351Y453508D01*
X187365Y453521D01*
Y453535D01*
X187518Y453785D01*
X187670Y454007D01*
X187809Y454201D01*
X187934Y454354D01*
X188031Y454492D01*
X188114Y454576D01*
X188170Y454645D01*
X188183Y454659D01*
X180681D01*
Y455838D01*
X190319D01*
Y455075D01*
D02*
G37*
G36*
X187754Y450249D02*
X188003Y450221D01*
X188225Y450165D01*
X188419Y450124D01*
X188586Y450068D01*
X188710Y450013D01*
X188780Y449985D01*
X188808Y449971D01*
X189016Y449860D01*
X189196Y449722D01*
X189362Y449597D01*
X189487Y449472D01*
X189584Y449361D01*
X189667Y449278D01*
X189709Y449222D01*
X189723Y449195D01*
X189834Y449014D01*
X189931Y448806D01*
X190014Y448612D01*
X190084Y448432D01*
X190125Y448265D01*
X190153Y448141D01*
X190181Y448044D01*
Y448016D01*
X190208Y447808D01*
X190236Y447572D01*
X190250Y447322D01*
X190264Y447087D01*
X190278Y446879D01*
Y442940D01*
X180681D01*
Y444216D01*
X184578D01*
Y446670D01*
X184592Y447031D01*
X184619Y447378D01*
X184661Y447683D01*
X184716Y447960D01*
X184772Y448224D01*
X184841Y448446D01*
X184925Y448654D01*
X185008Y448834D01*
X185077Y448987D01*
X185160Y449125D01*
X185230Y449236D01*
X185299Y449319D01*
X185340Y449389D01*
X185382Y449430D01*
X185410Y449458D01*
X185424Y449472D01*
X185590Y449611D01*
X185757Y449735D01*
X185923Y449832D01*
X186103Y449930D01*
X186284Y450013D01*
X186450Y450068D01*
X186769Y450165D01*
X186922Y450193D01*
X187060Y450221D01*
X187185Y450235D01*
X187282Y450249D01*
X187379Y450262D01*
X187435D01*
X187476D01*
X187490D01*
X187754Y450249D01*
D02*
G37*
G36*
X177319Y462417D02*
X177083Y462278D01*
X176862Y462125D01*
X176640Y461945D01*
X176446Y461779D01*
X176279Y461612D01*
X176140Y461488D01*
X176099Y461432D01*
X176057Y461390D01*
X176043Y461376D01*
X176029Y461363D01*
X175794Y461071D01*
X175572Y460780D01*
X175378Y460503D01*
X175225Y460225D01*
X175086Y459990D01*
X175031Y459893D01*
X174989Y459809D01*
X174948Y459740D01*
X174934Y459685D01*
X174906Y459657D01*
Y459643D01*
X173769D01*
X173852Y459851D01*
X173949Y460059D01*
X174046Y460267D01*
X174143Y460461D01*
X174227Y460628D01*
X174296Y460766D01*
X174351Y460849D01*
X174365Y460863D01*
Y460877D01*
X174518Y461127D01*
X174670Y461349D01*
X174809Y461543D01*
X174934Y461696D01*
X175031Y461834D01*
X175114Y461917D01*
X175170Y461987D01*
X175184Y462001D01*
X167681D01*
Y463179D01*
X177319D01*
Y462417D01*
D02*
G37*
G36*
Y454955D02*
X177083Y454817D01*
X176862Y454664D01*
X176640Y454484D01*
X176446Y454318D01*
X176279Y454151D01*
X176140Y454026D01*
X176099Y453971D01*
X176057Y453929D01*
X176043Y453915D01*
X176029Y453901D01*
X175794Y453610D01*
X175572Y453319D01*
X175378Y453042D01*
X175225Y452764D01*
X175086Y452528D01*
X175031Y452431D01*
X174989Y452348D01*
X174948Y452279D01*
X174934Y452223D01*
X174906Y452196D01*
Y452182D01*
X173769D01*
X173852Y452390D01*
X173949Y452598D01*
X174046Y452806D01*
X174143Y453000D01*
X174227Y453166D01*
X174296Y453305D01*
X174351Y453388D01*
X174365Y453402D01*
Y453416D01*
X174518Y453666D01*
X174670Y453888D01*
X174809Y454082D01*
X174934Y454234D01*
X175031Y454373D01*
X175114Y454456D01*
X175170Y454525D01*
X175184Y454539D01*
X167681D01*
Y455718D01*
X177319D01*
Y454955D01*
D02*
G37*
G36*
X174754Y450129D02*
X175003Y450102D01*
X175225Y450046D01*
X175419Y450004D01*
X175586Y449949D01*
X175711Y449893D01*
X175780Y449866D01*
X175808Y449852D01*
X176016Y449741D01*
X176196Y449602D01*
X176362Y449477D01*
X176487Y449353D01*
X176584Y449242D01*
X176667Y449159D01*
X176709Y449103D01*
X176723Y449075D01*
X176834Y448895D01*
X176931Y448687D01*
X177014Y448493D01*
X177083Y448312D01*
X177125Y448146D01*
X177153Y448021D01*
X177181Y447924D01*
Y447896D01*
X177208Y447688D01*
X177236Y447453D01*
X177250Y447203D01*
X177264Y446967D01*
X177278Y446759D01*
Y442821D01*
X167681D01*
Y444096D01*
X171578D01*
Y446551D01*
X171592Y446912D01*
X171619Y447258D01*
X171661Y447564D01*
X171716Y447841D01*
X171772Y448105D01*
X171841Y448326D01*
X171924Y448534D01*
X172008Y448715D01*
X172077Y448867D01*
X172160Y449006D01*
X172230Y449117D01*
X172299Y449200D01*
X172341Y449269D01*
X172382Y449311D01*
X172410Y449339D01*
X172424Y449353D01*
X172590Y449491D01*
X172757Y449616D01*
X172923Y449713D01*
X173103Y449810D01*
X173284Y449893D01*
X173450Y449949D01*
X173769Y450046D01*
X173922Y450074D01*
X174060Y450102D01*
X174185Y450115D01*
X174282Y450129D01*
X174379Y450143D01*
X174435D01*
X174476D01*
X174490D01*
X174754Y450129D01*
D02*
G37*
G36*
X440257Y198469D02*
X440632Y198399D01*
X440951Y198288D01*
X441228Y198178D01*
X441353Y198108D01*
X441450Y198053D01*
X441547Y197997D01*
X441616Y197942D01*
X441672Y197900D01*
X441713Y197872D01*
X441741Y197859D01*
X441755Y197845D01*
X442018Y197581D01*
X442226Y197290D01*
X442393Y196985D01*
X442532Y196680D01*
X442615Y196416D01*
X442656Y196305D01*
X442684Y196208D01*
X442698Y196125D01*
X442712Y196070D01*
X442726Y196028D01*
Y196014D01*
X441547Y195806D01*
X441491Y196111D01*
X441408Y196375D01*
X441311Y196597D01*
X441214Y196777D01*
X441117Y196915D01*
X441034Y197013D01*
X440978Y197082D01*
X440964Y197096D01*
X440784Y197234D01*
X440590Y197345D01*
X440410Y197415D01*
X440229Y197470D01*
X440063Y197498D01*
X439938Y197526D01*
X439827D01*
X439578Y197512D01*
X439356Y197456D01*
X439161Y197387D01*
X438995Y197318D01*
X438870Y197234D01*
X438773Y197165D01*
X438704Y197110D01*
X438690Y197096D01*
X438537Y196929D01*
X438427Y196749D01*
X438357Y196569D01*
X438302Y196402D01*
X438274Y196250D01*
X438246Y196139D01*
Y196056D01*
Y196042D01*
Y196028D01*
Y195875D01*
X438274Y195737D01*
X438343Y195501D01*
X438440Y195293D01*
X438551Y195113D01*
X438662Y194988D01*
X438759Y194891D01*
X438829Y194835D01*
X438843Y194821D01*
X438856D01*
X439092Y194697D01*
X439314Y194599D01*
X439550Y194530D01*
X439758Y194489D01*
X439938Y194461D01*
X440091Y194433D01*
X440271D01*
X440326Y194447D01*
X440396D01*
X440535Y193407D01*
X440354Y193448D01*
X440188Y193476D01*
X440049Y193504D01*
X439924Y193518D01*
X439827Y193532D01*
X439702D01*
X439411Y193504D01*
X439148Y193448D01*
X438912Y193365D01*
X438718Y193268D01*
X438565Y193171D01*
X438454Y193088D01*
X438385Y193032D01*
X438357Y193005D01*
X438177Y192797D01*
X438038Y192575D01*
X437941Y192353D01*
X437886Y192131D01*
X437844Y191951D01*
X437830Y191798D01*
X437816Y191743D01*
Y191701D01*
Y191673D01*
Y191659D01*
X437844Y191354D01*
X437913Y191077D01*
X437997Y190841D01*
X438107Y190633D01*
X438218Y190467D01*
X438302Y190342D01*
X438371Y190259D01*
X438399Y190231D01*
X438621Y190037D01*
X438856Y189898D01*
X439092Y189801D01*
X439314Y189732D01*
X439508Y189690D01*
X439661Y189676D01*
X439716Y189662D01*
X439799D01*
X440049Y189676D01*
X440285Y189732D01*
X440493Y189801D01*
X440659Y189884D01*
X440798Y189953D01*
X440909Y190023D01*
X440964Y190078D01*
X440992Y190092D01*
X441159Y190286D01*
X441297Y190508D01*
X441422Y190744D01*
X441519Y190994D01*
X441589Y191202D01*
X441616Y191299D01*
X441630Y191382D01*
X441644Y191451D01*
X441658Y191507D01*
X441672Y191535D01*
Y191548D01*
X442850Y191396D01*
X442823Y191174D01*
X442781Y190966D01*
X442656Y190578D01*
X442504Y190245D01*
X442421Y190106D01*
X442337Y189967D01*
X442254Y189843D01*
X442171Y189746D01*
X442102Y189648D01*
X442032Y189579D01*
X441991Y189524D01*
X441949Y189482D01*
X441921Y189454D01*
X441907Y189440D01*
X441741Y189316D01*
X441575Y189191D01*
X441408Y189094D01*
X441228Y189011D01*
X440881Y188872D01*
X440548Y188789D01*
X440396Y188761D01*
X440257Y188733D01*
X440132Y188719D01*
X440021Y188705D01*
X439938Y188692D01*
X439813D01*
X439550Y188705D01*
X439314Y188733D01*
X439078Y188775D01*
X438856Y188830D01*
X438648Y188899D01*
X438468Y188969D01*
X438288Y189052D01*
X438135Y189135D01*
X437983Y189205D01*
X437858Y189288D01*
X437747Y189357D01*
X437664Y189426D01*
X437594Y189482D01*
X437539Y189524D01*
X437511Y189551D01*
X437497Y189565D01*
X437331Y189732D01*
X437192Y189912D01*
X437067Y190092D01*
X436956Y190273D01*
X436873Y190439D01*
X436790Y190619D01*
X436679Y190952D01*
X436651Y191105D01*
X436624Y191243D01*
X436596Y191368D01*
X436582Y191479D01*
X436568Y191562D01*
Y191632D01*
Y191673D01*
Y191687D01*
X436582Y192020D01*
X436637Y192325D01*
X436721Y192589D01*
X436804Y192810D01*
X436887Y192991D01*
X436970Y193129D01*
X437026Y193213D01*
X437040Y193240D01*
X437234Y193448D01*
X437442Y193629D01*
X437664Y193767D01*
X437886Y193878D01*
X438080Y193962D01*
X438232Y194017D01*
X438288Y194031D01*
X438329Y194045D01*
X438357Y194059D01*
X438371D01*
X438135Y194183D01*
X437941Y194308D01*
X437775Y194447D01*
X437636Y194572D01*
X437525Y194683D01*
X437442Y194780D01*
X437400Y194835D01*
X437386Y194863D01*
X437275Y195057D01*
X437192Y195251D01*
X437123Y195445D01*
X437081Y195626D01*
X437053Y195778D01*
X437040Y195889D01*
Y195972D01*
Y196000D01*
X437053Y196236D01*
X437095Y196472D01*
X437151Y196680D01*
X437220Y196860D01*
X437289Y197013D01*
X437345Y197137D01*
X437386Y197207D01*
X437400Y197234D01*
X437539Y197442D01*
X437705Y197623D01*
X437872Y197775D01*
X438038Y197914D01*
X438177Y198011D01*
X438302Y198094D01*
X438385Y198136D01*
X438399Y198150D01*
X438413D01*
X438662Y198261D01*
X438912Y198344D01*
X439161Y198413D01*
X439383Y198455D01*
X439564Y198483D01*
X439716Y198496D01*
X440063D01*
X440257Y198469D01*
D02*
G37*
G36*
X432477Y198483D02*
X432713Y198469D01*
X432935Y198427D01*
X433143Y198386D01*
X433337Y198330D01*
X433517Y198275D01*
X433684Y198205D01*
X433836Y198136D01*
X433975Y198067D01*
X434086Y197997D01*
X434183Y197942D01*
X434266Y197886D01*
X434335Y197845D01*
X434377Y197803D01*
X434405Y197789D01*
X434418Y197775D01*
X434557Y197637D01*
X434682Y197484D01*
X434807Y197318D01*
X434904Y197151D01*
X435070Y196818D01*
X435181Y196486D01*
X435223Y196333D01*
X435265Y196180D01*
X435292Y196056D01*
X435320Y195945D01*
X435334Y195848D01*
Y195778D01*
X435348Y195737D01*
Y195723D01*
X434141Y195598D01*
X434113Y195917D01*
X434058Y196194D01*
X433975Y196444D01*
X433878Y196638D01*
X433794Y196805D01*
X433711Y196915D01*
X433656Y196985D01*
X433628Y197013D01*
X433420Y197179D01*
X433198Y197304D01*
X432962Y197401D01*
X432754Y197456D01*
X432560Y197498D01*
X432394Y197512D01*
X432338Y197526D01*
X432255D01*
X431964Y197512D01*
X431700Y197456D01*
X431478Y197373D01*
X431284Y197290D01*
X431132Y197193D01*
X431035Y197124D01*
X430965Y197068D01*
X430938Y197040D01*
X430771Y196846D01*
X430646Y196652D01*
X430549Y196458D01*
X430494Y196264D01*
X430452Y196111D01*
X430438Y195972D01*
X430424Y195889D01*
Y195875D01*
Y195861D01*
X430452Y195612D01*
X430508Y195348D01*
X430605Y195113D01*
X430702Y194891D01*
X430813Y194710D01*
X430910Y194558D01*
X430938Y194502D01*
X430965Y194461D01*
X430993Y194447D01*
Y194433D01*
X431104Y194280D01*
X431243Y194128D01*
X431395Y193962D01*
X431562Y193795D01*
X431908Y193462D01*
X432255Y193129D01*
X432435Y192977D01*
X432588Y192838D01*
X432740Y192713D01*
X432865Y192602D01*
X432962Y192519D01*
X433046Y192450D01*
X433101Y192408D01*
X433115Y192394D01*
X433462Y192103D01*
X433781Y191826D01*
X434044Y191576D01*
X434252Y191368D01*
X434432Y191188D01*
X434557Y191063D01*
X434627Y190980D01*
X434654Y190966D01*
Y190952D01*
X434848Y190716D01*
X435001Y190494D01*
X435140Y190273D01*
X435251Y190078D01*
X435334Y189912D01*
X435389Y189787D01*
X435417Y189704D01*
X435431Y189690D01*
Y189676D01*
X435486Y189524D01*
X435514Y189385D01*
X435542Y189246D01*
X435556Y189121D01*
X435570Y189011D01*
Y188927D01*
Y188872D01*
Y188858D01*
X429204D01*
Y189995D01*
X433933D01*
X433767Y190231D01*
X433684Y190328D01*
X433614Y190425D01*
X433545Y190508D01*
X433489Y190564D01*
X433448Y190605D01*
X433434Y190619D01*
X433364Y190689D01*
X433281Y190758D01*
X433087Y190938D01*
X432865Y191146D01*
X432630Y191354D01*
X432408Y191535D01*
X432310Y191618D01*
X432227Y191701D01*
X432158Y191756D01*
X432103Y191798D01*
X432075Y191826D01*
X432061Y191840D01*
X431839Y192034D01*
X431617Y192214D01*
X431423Y192394D01*
X431243Y192547D01*
X431076Y192700D01*
X430938Y192838D01*
X430799Y192963D01*
X430688Y193074D01*
X430577Y193185D01*
X430494Y193268D01*
X430424Y193337D01*
X430355Y193407D01*
X430286Y193490D01*
X430258Y193518D01*
X430064Y193754D01*
X429897Y193962D01*
X429759Y194170D01*
X429648Y194336D01*
X429565Y194489D01*
X429509Y194599D01*
X429481Y194669D01*
X429468Y194697D01*
X429384Y194905D01*
X429329Y195113D01*
X429273Y195307D01*
X429246Y195473D01*
X429232Y195626D01*
X429218Y195737D01*
Y195806D01*
Y195834D01*
X429232Y196042D01*
X429259Y196236D01*
X429287Y196430D01*
X429343Y196597D01*
X429481Y196929D01*
X429620Y197193D01*
X429703Y197318D01*
X429773Y197415D01*
X429842Y197512D01*
X429911Y197581D01*
X429967Y197637D01*
X429995Y197692D01*
X430022Y197706D01*
X430036Y197720D01*
X430189Y197859D01*
X430355Y197983D01*
X430535Y198080D01*
X430716Y198164D01*
X431076Y198302D01*
X431437Y198399D01*
X431589Y198427D01*
X431742Y198455D01*
X431881Y198469D01*
X431992Y198483D01*
X432089Y198496D01*
X432227D01*
X432477Y198483D01*
D02*
G37*
G36*
X452045Y188858D02*
X450769D01*
Y193116D01*
X449133D01*
X448980Y193102D01*
X448869D01*
X448772Y193088D01*
X448703Y193074D01*
X448647D01*
X448620Y193060D01*
X448606D01*
X448384Y192991D01*
X448287Y192949D01*
X448204Y192908D01*
X448120Y192866D01*
X448065Y192838D01*
X448037Y192824D01*
X448023Y192810D01*
X447912Y192727D01*
X447802Y192630D01*
X447593Y192422D01*
X447496Y192325D01*
X447427Y192242D01*
X447385Y192186D01*
X447372Y192173D01*
X447233Y191978D01*
X447080Y191770D01*
X446928Y191548D01*
X446775Y191340D01*
X446650Y191146D01*
X446553Y190994D01*
X446512Y190938D01*
X446484Y190897D01*
X446456Y190869D01*
Y190855D01*
X445194Y188858D01*
X443613D01*
X445264Y191465D01*
X445458Y191743D01*
X445638Y191992D01*
X445818Y192200D01*
X445971Y192394D01*
X446110Y192533D01*
X446221Y192644D01*
X446290Y192713D01*
X446318Y192741D01*
X446428Y192824D01*
X446553Y192921D01*
X446803Y193074D01*
X446914Y193129D01*
X446997Y193185D01*
X447053Y193213D01*
X447080Y193227D01*
X446831Y193268D01*
X446595Y193310D01*
X446387Y193379D01*
X446179Y193435D01*
X445999Y193504D01*
X445832Y193587D01*
X445680Y193656D01*
X445541Y193726D01*
X445430Y193809D01*
X445319Y193878D01*
X445236Y193934D01*
X445167Y193989D01*
X445111Y194031D01*
X445069Y194072D01*
X445056Y194086D01*
X445042Y194100D01*
X444931Y194239D01*
X444820Y194378D01*
X444653Y194669D01*
X444542Y194960D01*
X444459Y195237D01*
X444404Y195473D01*
X444390Y195570D01*
Y195667D01*
X444376Y195737D01*
Y195792D01*
Y195820D01*
Y195834D01*
X444390Y196125D01*
X444431Y196388D01*
X444501Y196638D01*
X444570Y196846D01*
X444653Y197026D01*
X444709Y197165D01*
X444764Y197248D01*
X444778Y197262D01*
Y197276D01*
X444945Y197498D01*
X445111Y197692D01*
X445291Y197859D01*
X445458Y197983D01*
X445610Y198080D01*
X445735Y198136D01*
X445818Y198178D01*
X445832Y198191D01*
X445846D01*
X445971Y198233D01*
X446123Y198275D01*
X446428Y198344D01*
X446761Y198386D01*
X447066Y198427D01*
X447358Y198441D01*
X447482D01*
X447593Y198455D01*
X452045D01*
Y188858D01*
D02*
G37*
G36*
X383335Y198469D02*
X383710Y198399D01*
X384029Y198288D01*
X384306Y198178D01*
X384431Y198108D01*
X384528Y198053D01*
X384625Y197997D01*
X384695Y197942D01*
X384750Y197900D01*
X384792Y197872D01*
X384819Y197859D01*
X384833Y197845D01*
X385097Y197581D01*
X385305Y197290D01*
X385471Y196985D01*
X385610Y196680D01*
X385693Y196416D01*
X385735Y196305D01*
X385762Y196208D01*
X385776Y196125D01*
X385790Y196070D01*
X385804Y196028D01*
Y196014D01*
X384625Y195806D01*
X384570Y196111D01*
X384487Y196375D01*
X384389Y196597D01*
X384292Y196777D01*
X384195Y196915D01*
X384112Y197013D01*
X384057Y197082D01*
X384043Y197096D01*
X383862Y197234D01*
X383668Y197345D01*
X383488Y197415D01*
X383308Y197470D01*
X383141Y197498D01*
X383016Y197526D01*
X382906D01*
X382656Y197512D01*
X382434Y197456D01*
X382240Y197387D01*
X382073Y197318D01*
X381949Y197234D01*
X381852Y197165D01*
X381782Y197110D01*
X381768Y197096D01*
X381616Y196929D01*
X381505Y196749D01*
X381435Y196569D01*
X381380Y196402D01*
X381352Y196250D01*
X381325Y196139D01*
Y196056D01*
Y196042D01*
Y196028D01*
Y195875D01*
X381352Y195737D01*
X381422Y195501D01*
X381519Y195293D01*
X381630Y195113D01*
X381740Y194988D01*
X381838Y194891D01*
X381907Y194835D01*
X381921Y194821D01*
X381935D01*
X382170Y194697D01*
X382392Y194599D01*
X382628Y194530D01*
X382836Y194489D01*
X383016Y194461D01*
X383169Y194433D01*
X383349D01*
X383405Y194447D01*
X383474D01*
X383613Y193407D01*
X383433Y193448D01*
X383266Y193476D01*
X383127Y193504D01*
X383003Y193518D01*
X382906Y193532D01*
X382781D01*
X382489Y193504D01*
X382226Y193448D01*
X381990Y193365D01*
X381796Y193268D01*
X381643Y193171D01*
X381533Y193088D01*
X381463Y193032D01*
X381435Y193005D01*
X381255Y192797D01*
X381116Y192575D01*
X381019Y192353D01*
X380964Y192131D01*
X380922Y191951D01*
X380908Y191798D01*
X380895Y191743D01*
Y191701D01*
Y191673D01*
Y191659D01*
X380922Y191354D01*
X380992Y191077D01*
X381075Y190841D01*
X381186Y190633D01*
X381297Y190467D01*
X381380Y190342D01*
X381449Y190259D01*
X381477Y190231D01*
X381699Y190037D01*
X381935Y189898D01*
X382170Y189801D01*
X382392Y189732D01*
X382587Y189690D01*
X382739Y189676D01*
X382794Y189662D01*
X382878D01*
X383127Y189676D01*
X383363Y189732D01*
X383571Y189801D01*
X383738Y189884D01*
X383876Y189953D01*
X383987Y190023D01*
X384043Y190078D01*
X384070Y190092D01*
X384237Y190286D01*
X384375Y190508D01*
X384500Y190744D01*
X384597Y190994D01*
X384667Y191202D01*
X384695Y191299D01*
X384708Y191382D01*
X384722Y191451D01*
X384736Y191507D01*
X384750Y191535D01*
Y191548D01*
X385929Y191396D01*
X385901Y191174D01*
X385859Y190966D01*
X385735Y190578D01*
X385582Y190245D01*
X385499Y190106D01*
X385416Y189967D01*
X385332Y189843D01*
X385249Y189746D01*
X385180Y189648D01*
X385111Y189579D01*
X385069Y189524D01*
X385027Y189482D01*
X385000Y189454D01*
X384986Y189440D01*
X384819Y189316D01*
X384653Y189191D01*
X384487Y189094D01*
X384306Y189011D01*
X383960Y188872D01*
X383627Y188789D01*
X383474Y188761D01*
X383335Y188733D01*
X383211Y188719D01*
X383100Y188705D01*
X383016Y188692D01*
X382892D01*
X382628Y188705D01*
X382392Y188733D01*
X382157Y188775D01*
X381935Y188830D01*
X381727Y188899D01*
X381546Y188969D01*
X381366Y189052D01*
X381213Y189135D01*
X381061Y189205D01*
X380936Y189288D01*
X380825Y189357D01*
X380742Y189426D01*
X380673Y189482D01*
X380617Y189524D01*
X380589Y189551D01*
X380576Y189565D01*
X380409Y189732D01*
X380271Y189912D01*
X380146Y190092D01*
X380035Y190273D01*
X379952Y190439D01*
X379868Y190619D01*
X379757Y190952D01*
X379730Y191105D01*
X379702Y191243D01*
X379674Y191368D01*
X379660Y191479D01*
X379646Y191562D01*
Y191632D01*
Y191673D01*
Y191687D01*
X379660Y192020D01*
X379716Y192325D01*
X379799Y192589D01*
X379882Y192810D01*
X379965Y192991D01*
X380049Y193129D01*
X380104Y193213D01*
X380118Y193240D01*
X380312Y193448D01*
X380520Y193629D01*
X380742Y193767D01*
X380964Y193878D01*
X381158Y193962D01*
X381311Y194017D01*
X381366Y194031D01*
X381408Y194045D01*
X381435Y194059D01*
X381449D01*
X381213Y194183D01*
X381019Y194308D01*
X380853Y194447D01*
X380714Y194572D01*
X380603Y194683D01*
X380520Y194780D01*
X380479Y194835D01*
X380465Y194863D01*
X380354Y195057D01*
X380271Y195251D01*
X380201Y195445D01*
X380159Y195626D01*
X380132Y195778D01*
X380118Y195889D01*
Y195972D01*
Y196000D01*
X380132Y196236D01*
X380173Y196472D01*
X380229Y196680D01*
X380298Y196860D01*
X380368Y197013D01*
X380423Y197137D01*
X380465Y197207D01*
X380479Y197234D01*
X380617Y197442D01*
X380784Y197623D01*
X380950Y197775D01*
X381116Y197914D01*
X381255Y198011D01*
X381380Y198094D01*
X381463Y198136D01*
X381477Y198150D01*
X381491D01*
X381740Y198261D01*
X381990Y198344D01*
X382240Y198413D01*
X382462Y198455D01*
X382642Y198483D01*
X382794Y198496D01*
X383141D01*
X383335Y198469D01*
D02*
G37*
G36*
X374945Y198261D02*
X375098Y198039D01*
X375278Y197817D01*
X375444Y197623D01*
X375611Y197456D01*
X375736Y197318D01*
X375791Y197276D01*
X375833Y197234D01*
X375846Y197221D01*
X375860Y197207D01*
X376152Y196971D01*
X376443Y196749D01*
X376720Y196555D01*
X376997Y196402D01*
X377233Y196264D01*
X377330Y196208D01*
X377414Y196167D01*
X377483Y196125D01*
X377538Y196111D01*
X377566Y196083D01*
X377580D01*
Y194946D01*
X377372Y195029D01*
X377164Y195126D01*
X376956Y195224D01*
X376762Y195321D01*
X376595Y195404D01*
X376457Y195473D01*
X376373Y195529D01*
X376360Y195543D01*
X376346D01*
X376096Y195695D01*
X375874Y195848D01*
X375680Y195986D01*
X375527Y196111D01*
X375389Y196208D01*
X375306Y196291D01*
X375236Y196347D01*
X375222Y196361D01*
Y188858D01*
X374044D01*
Y198496D01*
X374806D01*
X374945Y198261D01*
D02*
G37*
G36*
X395123Y188858D02*
X393848D01*
Y193116D01*
X392211D01*
X392059Y193102D01*
X391948D01*
X391851Y193088D01*
X391781Y193074D01*
X391726D01*
X391698Y193060D01*
X391684D01*
X391462Y192991D01*
X391365Y192949D01*
X391282Y192908D01*
X391199Y192866D01*
X391143Y192838D01*
X391116Y192824D01*
X391102Y192810D01*
X390991Y192727D01*
X390880Y192630D01*
X390672Y192422D01*
X390575Y192325D01*
X390505Y192242D01*
X390464Y192186D01*
X390450Y192173D01*
X390311Y191978D01*
X390159Y191770D01*
X390006Y191548D01*
X389854Y191340D01*
X389729Y191146D01*
X389632Y190994D01*
X389590Y190938D01*
X389562Y190897D01*
X389535Y190869D01*
Y190855D01*
X388273Y188858D01*
X386692D01*
X388342Y191465D01*
X388536Y191743D01*
X388716Y191992D01*
X388897Y192200D01*
X389049Y192394D01*
X389188Y192533D01*
X389299Y192644D01*
X389368Y192713D01*
X389396Y192741D01*
X389507Y192824D01*
X389632Y192921D01*
X389881Y193074D01*
X389992Y193129D01*
X390075Y193185D01*
X390131Y193213D01*
X390159Y193227D01*
X389909Y193268D01*
X389673Y193310D01*
X389465Y193379D01*
X389257Y193435D01*
X389077Y193504D01*
X388910Y193587D01*
X388758Y193656D01*
X388619Y193726D01*
X388508Y193809D01*
X388397Y193878D01*
X388314Y193934D01*
X388245Y193989D01*
X388189Y194031D01*
X388148Y194072D01*
X388134Y194086D01*
X388120Y194100D01*
X388009Y194239D01*
X387898Y194378D01*
X387732Y194669D01*
X387621Y194960D01*
X387537Y195237D01*
X387482Y195473D01*
X387468Y195570D01*
Y195667D01*
X387454Y195737D01*
Y195792D01*
Y195820D01*
Y195834D01*
X387468Y196125D01*
X387510Y196388D01*
X387579Y196638D01*
X387649Y196846D01*
X387732Y197026D01*
X387787Y197165D01*
X387843Y197248D01*
X387856Y197262D01*
Y197276D01*
X388023Y197498D01*
X388189Y197692D01*
X388370Y197859D01*
X388536Y197983D01*
X388689Y198080D01*
X388813Y198136D01*
X388897Y198178D01*
X388910Y198191D01*
X388924D01*
X389049Y198233D01*
X389202Y198275D01*
X389507Y198344D01*
X389840Y198386D01*
X390145Y198427D01*
X390436Y198441D01*
X390561D01*
X390672Y198455D01*
X395123D01*
Y188858D01*
D02*
G37*
G36*
X383167Y310050D02*
X383542Y309981D01*
X383861Y309870D01*
X384138Y309759D01*
X384263Y309689D01*
X384360Y309634D01*
X384457Y309578D01*
X384526Y309523D01*
X384582Y309481D01*
X384623Y309454D01*
X384651Y309440D01*
X384665Y309426D01*
X384928Y309162D01*
X385136Y308871D01*
X385303Y308566D01*
X385442Y308261D01*
X385525Y307997D01*
X385566Y307887D01*
X385594Y307789D01*
X385608Y307706D01*
X385622Y307651D01*
X385636Y307609D01*
Y307595D01*
X384457Y307387D01*
X384401Y307692D01*
X384318Y307956D01*
X384221Y308178D01*
X384124Y308358D01*
X384027Y308497D01*
X383944Y308594D01*
X383888Y308663D01*
X383874Y308677D01*
X383694Y308816D01*
X383500Y308927D01*
X383320Y308996D01*
X383139Y309051D01*
X382973Y309079D01*
X382848Y309107D01*
X382737D01*
X382488Y309093D01*
X382266Y309038D01*
X382071Y308968D01*
X381905Y308899D01*
X381780Y308816D01*
X381683Y308746D01*
X381614Y308691D01*
X381600Y308677D01*
X381447Y308511D01*
X381337Y308330D01*
X381267Y308150D01*
X381212Y307984D01*
X381184Y307831D01*
X381156Y307720D01*
Y307637D01*
Y307623D01*
Y307609D01*
Y307457D01*
X381184Y307318D01*
X381253Y307082D01*
X381350Y306874D01*
X381461Y306694D01*
X381572Y306569D01*
X381669Y306472D01*
X381739Y306416D01*
X381753Y306403D01*
X381766D01*
X382002Y306278D01*
X382224Y306181D01*
X382460Y306111D01*
X382668Y306070D01*
X382848Y306042D01*
X383001Y306014D01*
X383181D01*
X383237Y306028D01*
X383306D01*
X383445Y304988D01*
X383264Y305030D01*
X383098Y305057D01*
X382959Y305085D01*
X382834Y305099D01*
X382737Y305113D01*
X382612D01*
X382321Y305085D01*
X382058Y305030D01*
X381822Y304946D01*
X381628Y304849D01*
X381475Y304752D01*
X381364Y304669D01*
X381295Y304614D01*
X381267Y304586D01*
X381087Y304378D01*
X380948Y304156D01*
X380851Y303934D01*
X380796Y303712D01*
X380754Y303532D01*
X380740Y303379D01*
X380726Y303324D01*
Y303282D01*
Y303255D01*
Y303241D01*
X380754Y302936D01*
X380823Y302658D01*
X380907Y302422D01*
X381018Y302214D01*
X381129Y302048D01*
X381212Y301923D01*
X381281Y301840D01*
X381309Y301812D01*
X381531Y301618D01*
X381766Y301479D01*
X382002Y301382D01*
X382224Y301313D01*
X382418Y301271D01*
X382571Y301257D01*
X382626Y301244D01*
X382710D01*
X382959Y301257D01*
X383195Y301313D01*
X383403Y301382D01*
X383569Y301465D01*
X383708Y301535D01*
X383819Y301604D01*
X383874Y301660D01*
X383902Y301674D01*
X384069Y301868D01*
X384207Y302090D01*
X384332Y302325D01*
X384429Y302575D01*
X384498Y302783D01*
X384526Y302880D01*
X384540Y302963D01*
X384554Y303033D01*
X384568Y303088D01*
X384582Y303116D01*
Y303130D01*
X385760Y302977D01*
X385733Y302755D01*
X385691Y302547D01*
X385566Y302159D01*
X385414Y301826D01*
X385331Y301687D01*
X385247Y301549D01*
X385164Y301424D01*
X385081Y301327D01*
X385012Y301230D01*
X384942Y301160D01*
X384901Y301105D01*
X384859Y301063D01*
X384831Y301036D01*
X384818Y301022D01*
X384651Y300897D01*
X384485Y300772D01*
X384318Y300675D01*
X384138Y300592D01*
X383791Y300453D01*
X383458Y300370D01*
X383306Y300342D01*
X383167Y300314D01*
X383042Y300301D01*
X382931Y300287D01*
X382848Y300273D01*
X382723D01*
X382460Y300287D01*
X382224Y300314D01*
X381988Y300356D01*
X381766Y300411D01*
X381558Y300481D01*
X381378Y300550D01*
X381198Y300633D01*
X381045Y300717D01*
X380893Y300786D01*
X380768Y300869D01*
X380657Y300938D01*
X380574Y301008D01*
X380504Y301063D01*
X380449Y301105D01*
X380421Y301133D01*
X380407Y301147D01*
X380241Y301313D01*
X380102Y301493D01*
X379977Y301674D01*
X379866Y301854D01*
X379783Y302020D01*
X379700Y302201D01*
X379589Y302533D01*
X379561Y302686D01*
X379534Y302825D01*
X379506Y302949D01*
X379492Y303060D01*
X379478Y303144D01*
Y303213D01*
Y303255D01*
Y303268D01*
X379492Y303601D01*
X379548Y303906D01*
X379631Y304170D01*
X379714Y304392D01*
X379797Y304572D01*
X379880Y304711D01*
X379936Y304794D01*
X379950Y304822D01*
X380144Y305030D01*
X380352Y305210D01*
X380574Y305349D01*
X380796Y305460D01*
X380990Y305543D01*
X381142Y305598D01*
X381198Y305612D01*
X381239Y305626D01*
X381267Y305640D01*
X381281D01*
X381045Y305765D01*
X380851Y305889D01*
X380685Y306028D01*
X380546Y306153D01*
X380435Y306264D01*
X380352Y306361D01*
X380310Y306416D01*
X380296Y306444D01*
X380185Y306638D01*
X380102Y306833D01*
X380033Y307027D01*
X379991Y307207D01*
X379964Y307360D01*
X379950Y307470D01*
Y307554D01*
Y307582D01*
X379964Y307817D01*
X380005Y308053D01*
X380061Y308261D01*
X380130Y308441D01*
X380199Y308594D01*
X380255Y308719D01*
X380296Y308788D01*
X380310Y308816D01*
X380449Y309024D01*
X380615Y309204D01*
X380782Y309357D01*
X380948Y309495D01*
X381087Y309592D01*
X381212Y309676D01*
X381295Y309717D01*
X381309Y309731D01*
X381323D01*
X381572Y309842D01*
X381822Y309925D01*
X382071Y309995D01*
X382293Y310036D01*
X382474Y310064D01*
X382626Y310078D01*
X382973D01*
X383167Y310050D01*
D02*
G37*
G36*
X394955Y300439D02*
X393679D01*
Y304697D01*
X392043D01*
X391890Y304683D01*
X391779D01*
X391682Y304669D01*
X391613Y304655D01*
X391558D01*
X391530Y304641D01*
X391516D01*
X391294Y304572D01*
X391197Y304530D01*
X391114Y304489D01*
X391031Y304447D01*
X390975Y304419D01*
X390947Y304406D01*
X390933Y304392D01*
X390822Y304308D01*
X390712Y304211D01*
X390504Y304003D01*
X390406Y303906D01*
X390337Y303823D01*
X390295Y303768D01*
X390282Y303754D01*
X390143Y303560D01*
X389990Y303352D01*
X389838Y303130D01*
X389685Y302922D01*
X389561Y302728D01*
X389463Y302575D01*
X389422Y302519D01*
X389394Y302478D01*
X389366Y302450D01*
Y302436D01*
X388104Y300439D01*
X386523D01*
X388174Y303046D01*
X388368Y303324D01*
X388548Y303573D01*
X388728Y303782D01*
X388881Y303976D01*
X389020Y304114D01*
X389131Y304225D01*
X389200Y304295D01*
X389228Y304322D01*
X389339Y304406D01*
X389463Y304503D01*
X389713Y304655D01*
X389824Y304711D01*
X389907Y304766D01*
X389963Y304794D01*
X389990Y304808D01*
X389741Y304849D01*
X389505Y304891D01*
X389297Y304960D01*
X389089Y305016D01*
X388909Y305085D01*
X388742Y305168D01*
X388590Y305238D01*
X388451Y305307D01*
X388340Y305390D01*
X388229Y305460D01*
X388146Y305515D01*
X388077Y305571D01*
X388021Y305612D01*
X387980Y305654D01*
X387966Y305668D01*
X387952Y305681D01*
X387841Y305820D01*
X387730Y305959D01*
X387563Y306250D01*
X387453Y306541D01*
X387369Y306819D01*
X387314Y307055D01*
X387300Y307152D01*
Y307249D01*
X387286Y307318D01*
Y307373D01*
Y307401D01*
Y307415D01*
X387300Y307706D01*
X387341Y307970D01*
X387411Y308219D01*
X387480Y308427D01*
X387563Y308608D01*
X387619Y308746D01*
X387674Y308830D01*
X387688Y308843D01*
Y308857D01*
X387855Y309079D01*
X388021Y309273D01*
X388201Y309440D01*
X388368Y309565D01*
X388520Y309662D01*
X388645Y309717D01*
X388728Y309759D01*
X388742Y309773D01*
X388756D01*
X388881Y309814D01*
X389034Y309856D01*
X389339Y309925D01*
X389671Y309967D01*
X389977Y310008D01*
X390268Y310022D01*
X390393D01*
X390504Y310036D01*
X394955D01*
Y300439D01*
D02*
G37*
G36*
X375553Y310050D02*
X375900Y309995D01*
X376191Y309897D01*
X376441Y309800D01*
X376649Y309689D01*
X376732Y309648D01*
X376802Y309592D01*
X376857Y309565D01*
X376899Y309537D01*
X376912Y309509D01*
X376926D01*
X377176Y309287D01*
X377384Y309024D01*
X377564Y308760D01*
X377703Y308511D01*
X377814Y308275D01*
X377869Y308178D01*
X377897Y308081D01*
X377925Y308011D01*
X377953Y307956D01*
X377966Y307928D01*
Y307914D01*
X378022Y307706D01*
X378078Y307498D01*
X378161Y307041D01*
X378230Y306583D01*
X378272Y306153D01*
X378285Y305945D01*
X378299Y305765D01*
Y305598D01*
X378313Y305446D01*
Y305335D01*
Y305238D01*
Y305182D01*
Y305168D01*
X378299Y304683D01*
X378272Y304225D01*
X378230Y303809D01*
X378161Y303421D01*
X378091Y303060D01*
X378008Y302741D01*
X377925Y302450D01*
X377842Y302201D01*
X377758Y301979D01*
X377661Y301784D01*
X377592Y301618D01*
X377523Y301493D01*
X377453Y301382D01*
X377412Y301313D01*
X377384Y301271D01*
X377370Y301257D01*
X377218Y301091D01*
X377051Y300938D01*
X376871Y300800D01*
X376691Y300689D01*
X376510Y300592D01*
X376330Y300509D01*
X376150Y300453D01*
X375983Y300398D01*
X375817Y300356D01*
X375664Y300328D01*
X375526Y300301D01*
X375415Y300287D01*
X375318Y300273D01*
X375179D01*
X374804Y300301D01*
X374458Y300356D01*
X374167Y300453D01*
X373917Y300550D01*
X373709Y300647D01*
X373640Y300703D01*
X373570Y300744D01*
X373515Y300772D01*
X373473Y300800D01*
X373459Y300828D01*
X373445D01*
X373196Y301063D01*
X372988Y301313D01*
X372808Y301590D01*
X372669Y301840D01*
X372558Y302076D01*
X372502Y302173D01*
X372475Y302270D01*
X372447Y302339D01*
X372419Y302395D01*
X372405Y302422D01*
Y302436D01*
X372336Y302644D01*
X372281Y302852D01*
X372197Y303296D01*
X372128Y303754D01*
X372086Y304198D01*
X372072Y304392D01*
X372059Y304572D01*
Y304738D01*
X372045Y304891D01*
Y305002D01*
Y305099D01*
Y305154D01*
Y305168D01*
Y305432D01*
X372059Y305681D01*
Y305903D01*
X372072Y306125D01*
X372100Y306319D01*
X372114Y306514D01*
X372128Y306680D01*
X372156Y306833D01*
X372169Y306971D01*
X372197Y307096D01*
X372211Y307193D01*
X372225Y307276D01*
X372239Y307346D01*
X372253Y307387D01*
X372267Y307415D01*
Y307429D01*
X372350Y307734D01*
X372447Y308011D01*
X372558Y308247D01*
X372641Y308455D01*
X372738Y308636D01*
X372794Y308760D01*
X372849Y308830D01*
X372863Y308857D01*
X373016Y309065D01*
X373168Y309246D01*
X373335Y309398D01*
X373487Y309537D01*
X373626Y309634D01*
X373737Y309703D01*
X373806Y309745D01*
X373820Y309759D01*
X373834D01*
X374056Y309870D01*
X374291Y309939D01*
X374513Y309995D01*
X374721Y310036D01*
X374902Y310064D01*
X375054Y310078D01*
X375179D01*
X375553Y310050D01*
D02*
G37*
G36*
X389619Y266139D02*
X389855Y266125D01*
X390077Y266083D01*
X390285Y266042D01*
X390479Y265986D01*
X390659Y265931D01*
X390826Y265861D01*
X390978Y265792D01*
X391117Y265723D01*
X391228Y265653D01*
X391325Y265598D01*
X391408Y265542D01*
X391477Y265501D01*
X391519Y265459D01*
X391547Y265445D01*
X391561Y265431D01*
X391699Y265293D01*
X391824Y265140D01*
X391949Y264974D01*
X392046Y264807D01*
X392212Y264474D01*
X392323Y264142D01*
X392365Y263989D01*
X392407Y263836D01*
X392434Y263712D01*
X392462Y263601D01*
X392476Y263504D01*
Y263434D01*
X392490Y263393D01*
Y263379D01*
X391283Y263254D01*
X391255Y263573D01*
X391200Y263850D01*
X391117Y264100D01*
X391020Y264294D01*
X390937Y264461D01*
X390853Y264571D01*
X390798Y264641D01*
X390770Y264669D01*
X390562Y264835D01*
X390340Y264960D01*
X390104Y265057D01*
X389896Y265112D01*
X389702Y265154D01*
X389536Y265168D01*
X389480Y265182D01*
X389397D01*
X389106Y265168D01*
X388842Y265112D01*
X388620Y265029D01*
X388426Y264946D01*
X388274Y264849D01*
X388177Y264779D01*
X388107Y264724D01*
X388080Y264696D01*
X387913Y264502D01*
X387788Y264308D01*
X387691Y264114D01*
X387636Y263920D01*
X387594Y263767D01*
X387580Y263628D01*
X387566Y263545D01*
Y263531D01*
Y263517D01*
X387594Y263268D01*
X387650Y263004D01*
X387747Y262769D01*
X387844Y262547D01*
X387955Y262366D01*
X388052Y262214D01*
X388080Y262158D01*
X388107Y262117D01*
X388135Y262103D01*
Y262089D01*
X388246Y261936D01*
X388385Y261784D01*
X388537Y261618D01*
X388704Y261451D01*
X389050Y261118D01*
X389397Y260785D01*
X389577Y260633D01*
X389730Y260494D01*
X389883Y260369D01*
X390007Y260258D01*
X390104Y260175D01*
X390188Y260106D01*
X390243Y260064D01*
X390257Y260050D01*
X390604Y259759D01*
X390923Y259482D01*
X391186Y259232D01*
X391394Y259024D01*
X391574Y258844D01*
X391699Y258719D01*
X391769Y258636D01*
X391796Y258622D01*
Y258608D01*
X391991Y258372D01*
X392143Y258150D01*
X392282Y257929D01*
X392393Y257734D01*
X392476Y257568D01*
X392531Y257443D01*
X392559Y257360D01*
X392573Y257346D01*
Y257332D01*
X392628Y257180D01*
X392656Y257041D01*
X392684Y256902D01*
X392698Y256777D01*
X392712Y256667D01*
Y256583D01*
Y256528D01*
Y256514D01*
X386346D01*
Y257651D01*
X391075D01*
X390909Y257887D01*
X390826Y257984D01*
X390756Y258081D01*
X390687Y258164D01*
X390631Y258220D01*
X390590Y258261D01*
X390576Y258275D01*
X390507Y258345D01*
X390423Y258414D01*
X390229Y258594D01*
X390007Y258802D01*
X389771Y259010D01*
X389550Y259191D01*
X389453Y259274D01*
X389369Y259357D01*
X389300Y259412D01*
X389244Y259454D01*
X389217Y259482D01*
X389203Y259496D01*
X388981Y259690D01*
X388759Y259870D01*
X388565Y260050D01*
X388385Y260203D01*
X388218Y260355D01*
X388080Y260494D01*
X387941Y260619D01*
X387830Y260730D01*
X387719Y260841D01*
X387636Y260924D01*
X387566Y260993D01*
X387497Y261063D01*
X387428Y261146D01*
X387400Y261174D01*
X387206Y261409D01*
X387039Y261618D01*
X386901Y261826D01*
X386790Y261992D01*
X386707Y262145D01*
X386651Y262255D01*
X386623Y262325D01*
X386609Y262353D01*
X386526Y262561D01*
X386471Y262769D01*
X386415Y262963D01*
X386388Y263129D01*
X386374Y263282D01*
X386360Y263393D01*
Y263462D01*
Y263490D01*
X386374Y263698D01*
X386401Y263892D01*
X386429Y264086D01*
X386485Y264252D01*
X386623Y264585D01*
X386762Y264849D01*
X386845Y264974D01*
X386915Y265071D01*
X386984Y265168D01*
X387053Y265237D01*
X387109Y265293D01*
X387136Y265348D01*
X387164Y265362D01*
X387178Y265376D01*
X387331Y265515D01*
X387497Y265639D01*
X387677Y265736D01*
X387858Y265820D01*
X388218Y265958D01*
X388579Y266055D01*
X388731Y266083D01*
X388884Y266111D01*
X389023Y266125D01*
X389134Y266139D01*
X389231Y266152D01*
X389369D01*
X389619Y266139D01*
D02*
G37*
G36*
X382310D02*
X382532Y266111D01*
X382754Y266069D01*
X382948Y266014D01*
X383323Y265861D01*
X383489Y265792D01*
X383628Y265709D01*
X383767Y265612D01*
X383877Y265542D01*
X383988Y265459D01*
X384072Y265390D01*
X384141Y265334D01*
X384183Y265293D01*
X384210Y265265D01*
X384224Y265251D01*
X384377Y265085D01*
X384501Y264890D01*
X384626Y264710D01*
X384723Y264516D01*
X384807Y264308D01*
X384876Y264114D01*
X384973Y263753D01*
X385015Y263573D01*
X385042Y263420D01*
X385056Y263268D01*
X385070Y263143D01*
X385084Y263046D01*
Y262977D01*
Y262921D01*
Y262907D01*
X385070Y262644D01*
X385042Y262408D01*
X385015Y262172D01*
X384959Y261950D01*
X384890Y261756D01*
X384821Y261562D01*
X384751Y261396D01*
X384668Y261243D01*
X384599Y261104D01*
X384529Y260980D01*
X384460Y260882D01*
X384391Y260785D01*
X384335Y260716D01*
X384307Y260674D01*
X384280Y260647D01*
X384266Y260633D01*
X384113Y260480D01*
X383947Y260355D01*
X383780Y260231D01*
X383600Y260134D01*
X383434Y260050D01*
X383267Y259981D01*
X382948Y259884D01*
X382810Y259842D01*
X382671Y259815D01*
X382560Y259801D01*
X382449Y259787D01*
X382366Y259773D01*
X382255D01*
X381991Y259787D01*
X381742Y259828D01*
X381520Y259884D01*
X381312Y259953D01*
X381159Y260009D01*
X381034Y260064D01*
X380951Y260106D01*
X380924Y260120D01*
X380702Y260258D01*
X380507Y260411D01*
X380341Y260564D01*
X380202Y260702D01*
X380105Y260841D01*
X380022Y260938D01*
X379967Y261007D01*
X379953Y261035D01*
Y260924D01*
Y260855D01*
Y260813D01*
Y260799D01*
X379967Y260522D01*
X379980Y260258D01*
X380008Y260023D01*
X380036Y259801D01*
X380078Y259620D01*
X380105Y259482D01*
X380119Y259426D01*
Y259385D01*
X380133Y259371D01*
Y259357D01*
X380202Y259107D01*
X380272Y258885D01*
X380341Y258691D01*
X380410Y258525D01*
X380466Y258400D01*
X380521Y258303D01*
X380549Y258234D01*
X380563Y258220D01*
X380674Y258067D01*
X380785Y257942D01*
X380896Y257831D01*
X381007Y257734D01*
X381090Y257651D01*
X381173Y257596D01*
X381229Y257568D01*
X381242Y257554D01*
X381395Y257471D01*
X381561Y257415D01*
X381714Y257374D01*
X381866Y257346D01*
X381991Y257332D01*
X382088Y257318D01*
X382186D01*
X382407Y257332D01*
X382615Y257374D01*
X382796Y257429D01*
X382948Y257499D01*
X383059Y257554D01*
X383156Y257610D01*
X383212Y257651D01*
X383226Y257665D01*
X383364Y257818D01*
X383475Y257998D01*
X383572Y258192D01*
X383642Y258386D01*
X383697Y258553D01*
X383739Y258705D01*
X383753Y258761D01*
Y258788D01*
X383767Y258816D01*
Y258830D01*
X384904Y258733D01*
X384821Y258331D01*
X384710Y257984D01*
X384571Y257679D01*
X384432Y257429D01*
X384294Y257235D01*
X384224Y257152D01*
X384169Y257083D01*
X384127Y257041D01*
X384086Y256999D01*
X384072Y256985D01*
X384058Y256972D01*
X383919Y256861D01*
X383767Y256764D01*
X383461Y256611D01*
X383156Y256500D01*
X382865Y256431D01*
X382602Y256375D01*
X382491Y256361D01*
X382393D01*
X382324Y256348D01*
X382213D01*
X381825Y256375D01*
X381478Y256431D01*
X381159Y256528D01*
X380896Y256639D01*
X380785Y256680D01*
X380674Y256736D01*
X380591Y256791D01*
X380507Y256833D01*
X380452Y256861D01*
X380410Y256888D01*
X380383Y256916D01*
X380369D01*
X380091Y257152D01*
X379842Y257415D01*
X379648Y257693D01*
X379481Y257956D01*
X379342Y258192D01*
X379287Y258303D01*
X379245Y258386D01*
X379218Y258469D01*
X379190Y258525D01*
X379176Y258553D01*
Y258566D01*
X379107Y258775D01*
X379037Y259010D01*
X378940Y259482D01*
X378871Y259981D01*
X378829Y260453D01*
X378802Y260661D01*
X378788Y260869D01*
Y261049D01*
X378774Y261201D01*
Y261326D01*
Y261423D01*
Y261493D01*
Y261507D01*
Y261826D01*
X378788Y262131D01*
X378815Y262408D01*
X378843Y262672D01*
X378871Y262907D01*
X378899Y263129D01*
X378940Y263337D01*
X378982Y263517D01*
X379024Y263670D01*
X379051Y263809D01*
X379093Y263934D01*
X379121Y264031D01*
X379148Y264100D01*
X379176Y264155D01*
X379190Y264183D01*
Y264197D01*
X379356Y264530D01*
X379537Y264821D01*
X379745Y265071D01*
X379925Y265279D01*
X380105Y265431D01*
X380244Y265542D01*
X380299Y265584D01*
X380341Y265612D01*
X380355Y265639D01*
X380369D01*
X380660Y265806D01*
X380951Y265931D01*
X381242Y266028D01*
X381506Y266083D01*
X381742Y266125D01*
X381839Y266139D01*
X381908D01*
X381978Y266152D01*
X382075D01*
X382310Y266139D01*
D02*
G37*
G36*
X401726Y256514D02*
X400450D01*
Y260772D01*
X398814D01*
X398661Y260758D01*
X398550D01*
X398453Y260744D01*
X398384Y260730D01*
X398328D01*
X398301Y260716D01*
X398287D01*
X398065Y260647D01*
X397968Y260605D01*
X397884Y260564D01*
X397801Y260522D01*
X397746Y260494D01*
X397718Y260480D01*
X397704Y260466D01*
X397593Y260383D01*
X397482Y260286D01*
X397274Y260078D01*
X397177Y259981D01*
X397108Y259898D01*
X397066Y259842D01*
X397052Y259828D01*
X396914Y259634D01*
X396761Y259426D01*
X396609Y259204D01*
X396456Y258996D01*
X396331Y258802D01*
X396234Y258650D01*
X396193Y258594D01*
X396165Y258553D01*
X396137Y258525D01*
Y258511D01*
X394875Y256514D01*
X393294D01*
X394944Y259121D01*
X395139Y259399D01*
X395319Y259648D01*
X395499Y259856D01*
X395652Y260050D01*
X395790Y260189D01*
X395901Y260300D01*
X395971Y260369D01*
X395998Y260397D01*
X396109Y260480D01*
X396234Y260577D01*
X396484Y260730D01*
X396595Y260785D01*
X396678Y260841D01*
X396734Y260869D01*
X396761Y260882D01*
X396512Y260924D01*
X396276Y260966D01*
X396068Y261035D01*
X395860Y261091D01*
X395680Y261160D01*
X395513Y261243D01*
X395360Y261312D01*
X395222Y261382D01*
X395111Y261465D01*
X395000Y261534D01*
X394917Y261590D01*
X394847Y261645D01*
X394792Y261687D01*
X394750Y261728D01*
X394736Y261742D01*
X394723Y261756D01*
X394612Y261895D01*
X394501Y262034D01*
X394334Y262325D01*
X394223Y262616D01*
X394140Y262893D01*
X394085Y263129D01*
X394071Y263226D01*
Y263323D01*
X394057Y263393D01*
Y263448D01*
Y263476D01*
Y263490D01*
X394071Y263781D01*
X394112Y264044D01*
X394182Y264294D01*
X394251Y264502D01*
X394334Y264682D01*
X394390Y264821D01*
X394445Y264904D01*
X394459Y264918D01*
Y264932D01*
X394626Y265154D01*
X394792Y265348D01*
X394972Y265515D01*
X395139Y265639D01*
X395291Y265736D01*
X395416Y265792D01*
X395499Y265833D01*
X395513Y265847D01*
X395527D01*
X395652Y265889D01*
X395804Y265931D01*
X396109Y266000D01*
X396442Y266042D01*
X396747Y266083D01*
X397039Y266097D01*
X397163D01*
X397274Y266111D01*
X401726D01*
Y256514D01*
D02*
G37*
G36*
X320362Y400889D02*
X320598Y400875D01*
X320820Y400833D01*
X321028Y400792D01*
X321222Y400736D01*
X321402Y400681D01*
X321569Y400611D01*
X321721Y400542D01*
X321860Y400473D01*
X321971Y400403D01*
X322068Y400348D01*
X322151Y400292D01*
X322220Y400251D01*
X322262Y400209D01*
X322290Y400195D01*
X322304Y400181D01*
X322442Y400043D01*
X322567Y399890D01*
X322692Y399724D01*
X322789Y399557D01*
X322955Y399224D01*
X323066Y398892D01*
X323108Y398739D01*
X323150Y398587D01*
X323177Y398462D01*
X323205Y398351D01*
X323219Y398254D01*
Y398184D01*
X323233Y398143D01*
Y398129D01*
X322026Y398004D01*
X321998Y398323D01*
X321943Y398600D01*
X321860Y398850D01*
X321763Y399044D01*
X321679Y399211D01*
X321596Y399322D01*
X321541Y399391D01*
X321513Y399419D01*
X321305Y399585D01*
X321083Y399710D01*
X320847Y399807D01*
X320639Y399862D01*
X320445Y399904D01*
X320279Y399918D01*
X320223Y399932D01*
X320140D01*
X319849Y399918D01*
X319585Y399862D01*
X319363Y399779D01*
X319169Y399696D01*
X319017Y399599D01*
X318920Y399529D01*
X318850Y399474D01*
X318823Y399446D01*
X318656Y399252D01*
X318531Y399058D01*
X318434Y398864D01*
X318379Y398670D01*
X318337Y398517D01*
X318323Y398378D01*
X318309Y398295D01*
Y398281D01*
Y398268D01*
X318337Y398018D01*
X318393Y397754D01*
X318490Y397519D01*
X318587Y397297D01*
X318698Y397116D01*
X318795Y396964D01*
X318823Y396908D01*
X318850Y396867D01*
X318878Y396853D01*
Y396839D01*
X318989Y396687D01*
X319128Y396534D01*
X319280Y396367D01*
X319447Y396201D01*
X319793Y395868D01*
X320140Y395535D01*
X320320Y395383D01*
X320473Y395244D01*
X320625Y395119D01*
X320750Y395008D01*
X320847Y394925D01*
X320931Y394856D01*
X320986Y394814D01*
X321000Y394800D01*
X321347Y394509D01*
X321666Y394232D01*
X321929Y393982D01*
X322137Y393774D01*
X322318Y393594D01*
X322442Y393469D01*
X322512Y393386D01*
X322539Y393372D01*
Y393358D01*
X322733Y393122D01*
X322886Y392900D01*
X323025Y392678D01*
X323136Y392484D01*
X323219Y392318D01*
X323274Y392193D01*
X323302Y392110D01*
X323316Y392096D01*
Y392082D01*
X323372Y391930D01*
X323399Y391791D01*
X323427Y391652D01*
X323441Y391527D01*
X323455Y391417D01*
Y391333D01*
Y391278D01*
Y391264D01*
X317089D01*
Y392401D01*
X321818D01*
X321652Y392637D01*
X321569Y392734D01*
X321499Y392831D01*
X321430Y392914D01*
X321374Y392970D01*
X321333Y393011D01*
X321319Y393025D01*
X321250Y393095D01*
X321166Y393164D01*
X320972Y393344D01*
X320750Y393552D01*
X320515Y393760D01*
X320293Y393941D01*
X320196Y394024D01*
X320112Y394107D01*
X320043Y394162D01*
X319988Y394204D01*
X319960Y394232D01*
X319946Y394246D01*
X319724Y394440D01*
X319502Y394620D01*
X319308Y394800D01*
X319128Y394953D01*
X318961Y395106D01*
X318823Y395244D01*
X318684Y395369D01*
X318573Y395480D01*
X318462Y395591D01*
X318379Y395674D01*
X318309Y395743D01*
X318240Y395813D01*
X318171Y395896D01*
X318143Y395924D01*
X317949Y396160D01*
X317782Y396367D01*
X317644Y396576D01*
X317533Y396742D01*
X317450Y396894D01*
X317394Y397006D01*
X317367Y397075D01*
X317353Y397103D01*
X317269Y397311D01*
X317214Y397519D01*
X317158Y397713D01*
X317131Y397879D01*
X317117Y398032D01*
X317103Y398143D01*
Y398212D01*
Y398240D01*
X317117Y398448D01*
X317145Y398642D01*
X317172Y398836D01*
X317228Y399002D01*
X317367Y399335D01*
X317505Y399599D01*
X317588Y399724D01*
X317658Y399821D01*
X317727Y399918D01*
X317796Y399987D01*
X317852Y400043D01*
X317880Y400098D01*
X317907Y400112D01*
X317921Y400126D01*
X318074Y400265D01*
X318240Y400389D01*
X318421Y400486D01*
X318601Y400570D01*
X318961Y400708D01*
X319322Y400805D01*
X319475Y400833D01*
X319627Y400861D01*
X319766Y400875D01*
X319877Y400889D01*
X319974Y400902D01*
X320112D01*
X320362Y400889D01*
D02*
G37*
G36*
X312707D02*
X312970Y400861D01*
X313220Y400805D01*
X313456Y400736D01*
X313664Y400639D01*
X313872Y400556D01*
X314052Y400445D01*
X314218Y400348D01*
X314357Y400251D01*
X314496Y400140D01*
X314607Y400056D01*
X314690Y399973D01*
X314759Y399890D01*
X314815Y399835D01*
X314842Y399807D01*
X314856Y399793D01*
X315037Y399543D01*
X315189Y399252D01*
X315328Y398947D01*
X315453Y398628D01*
X315550Y398295D01*
X315633Y397962D01*
X315702Y397616D01*
X315758Y397297D01*
X315799Y396978D01*
X315827Y396687D01*
X315855Y396423D01*
X315869Y396201D01*
Y396007D01*
X315883Y395868D01*
Y395813D01*
Y395771D01*
Y395757D01*
Y395743D01*
X315869Y395300D01*
X315841Y394884D01*
X315799Y394495D01*
X315730Y394135D01*
X315661Y393816D01*
X315591Y393525D01*
X315508Y393261D01*
X315411Y393025D01*
X315328Y392831D01*
X315245Y392651D01*
X315175Y392512D01*
X315092Y392387D01*
X315037Y392290D01*
X314995Y392235D01*
X314967Y392193D01*
X314953Y392179D01*
X314773Y391985D01*
X314579Y391819D01*
X314385Y391680D01*
X314191Y391555D01*
X313983Y391444D01*
X313788Y391361D01*
X313594Y391292D01*
X313400Y391236D01*
X313234Y391195D01*
X313067Y391153D01*
X312929Y391125D01*
X312804Y391111D01*
X312693D01*
X312624Y391097D01*
X312554D01*
X312235Y391111D01*
X311944Y391167D01*
X311680Y391222D01*
X311445Y391306D01*
X311264Y391375D01*
X311126Y391444D01*
X311070Y391458D01*
X311029Y391486D01*
X311015Y391500D01*
X311001D01*
X310765Y391666D01*
X310543Y391860D01*
X310363Y392054D01*
X310210Y392249D01*
X310086Y392429D01*
X310002Y392568D01*
X309975Y392623D01*
X309947Y392665D01*
X309933Y392678D01*
Y392692D01*
X309794Y392984D01*
X309697Y393289D01*
X309628Y393566D01*
X309586Y393830D01*
X309545Y394052D01*
Y394135D01*
X309531Y394218D01*
Y394287D01*
Y394329D01*
Y394357D01*
Y394370D01*
X309545Y394620D01*
X309572Y394856D01*
X309614Y395092D01*
X309656Y395300D01*
X309725Y395494D01*
X309794Y395688D01*
X309864Y395854D01*
X309947Y396007D01*
X310030Y396146D01*
X310099Y396270D01*
X310169Y396367D01*
X310238Y396465D01*
X310280Y396534D01*
X310321Y396576D01*
X310349Y396603D01*
X310363Y396617D01*
X310515Y396770D01*
X310682Y396908D01*
X310862Y397019D01*
X311029Y397116D01*
X311195Y397214D01*
X311362Y397283D01*
X311680Y397380D01*
X311819Y397421D01*
X311958Y397449D01*
X312069Y397463D01*
X312180Y397477D01*
X312263Y397491D01*
X312374D01*
X312624Y397477D01*
X312859Y397435D01*
X313081Y397394D01*
X313275Y397338D01*
X313442Y397269D01*
X313566Y397227D01*
X313650Y397186D01*
X313664Y397172D01*
X313678D01*
X313899Y397033D01*
X314093Y396881D01*
X314274Y396728D01*
X314412Y396562D01*
X314537Y396423D01*
X314634Y396312D01*
X314690Y396229D01*
X314704Y396215D01*
Y396465D01*
X314690Y396714D01*
X314676Y396936D01*
X314648Y397158D01*
X314634Y397352D01*
X314607Y397533D01*
X314579Y397699D01*
X314537Y397851D01*
X314510Y397990D01*
X314482Y398101D01*
X314454Y398198D01*
X314440Y398281D01*
X314412Y398337D01*
X314399Y398378D01*
X314385Y398406D01*
Y398420D01*
X314246Y398697D01*
X314107Y398947D01*
X313955Y399141D01*
X313816Y399308D01*
X313691Y399446D01*
X313594Y399543D01*
X313525Y399599D01*
X313497Y399613D01*
X313331Y399724D01*
X313164Y399793D01*
X312998Y399849D01*
X312831Y399890D01*
X312707Y399918D01*
X312596Y399932D01*
X312499D01*
X312249Y399904D01*
X312013Y399849D01*
X311819Y399765D01*
X311639Y399682D01*
X311500Y399585D01*
X311403Y399502D01*
X311348Y399446D01*
X311320Y399419D01*
X311223Y399294D01*
X311126Y399141D01*
X311042Y398975D01*
X310987Y398808D01*
X310931Y398656D01*
X310890Y398531D01*
X310876Y398448D01*
X310862Y398434D01*
Y398420D01*
X309683Y398517D01*
X309767Y398905D01*
X309891Y399252D01*
X310030Y399557D01*
X310183Y399807D01*
X310335Y400001D01*
X310391Y400084D01*
X310460Y400154D01*
X310502Y400195D01*
X310543Y400237D01*
X310557Y400251D01*
X310571Y400265D01*
X310710Y400376D01*
X310862Y400473D01*
X311167Y400639D01*
X311472Y400750D01*
X311764Y400819D01*
X312027Y400875D01*
X312138Y400889D01*
X312235D01*
X312318Y400902D01*
X312429D01*
X312707Y400889D01*
D02*
G37*
G36*
X332469Y391264D02*
X331193D01*
Y395522D01*
X329557D01*
X329404Y395508D01*
X329293D01*
X329196Y395494D01*
X329127Y395480D01*
X329071D01*
X329044Y395466D01*
X329030D01*
X328808Y395397D01*
X328711Y395355D01*
X328628Y395313D01*
X328544Y395272D01*
X328489Y395244D01*
X328461Y395230D01*
X328447Y395216D01*
X328336Y395133D01*
X328225Y395036D01*
X328017Y394828D01*
X327920Y394731D01*
X327851Y394648D01*
X327809Y394592D01*
X327795Y394579D01*
X327657Y394384D01*
X327504Y394176D01*
X327352Y393954D01*
X327199Y393746D01*
X327074Y393552D01*
X326977Y393400D01*
X326936Y393344D01*
X326908Y393303D01*
X326880Y393275D01*
Y393261D01*
X325618Y391264D01*
X324037D01*
X325687Y393871D01*
X325882Y394149D01*
X326062Y394398D01*
X326242Y394606D01*
X326395Y394800D01*
X326534Y394939D01*
X326644Y395050D01*
X326714Y395119D01*
X326741Y395147D01*
X326852Y395230D01*
X326977Y395327D01*
X327227Y395480D01*
X327338Y395535D01*
X327421Y395591D01*
X327477Y395619D01*
X327504Y395633D01*
X327255Y395674D01*
X327019Y395716D01*
X326811Y395785D01*
X326603Y395840D01*
X326423Y395910D01*
X326256Y395993D01*
X326104Y396062D01*
X325965Y396132D01*
X325854Y396215D01*
X325743Y396284D01*
X325660Y396340D01*
X325590Y396395D01*
X325535Y396437D01*
X325493Y396479D01*
X325480Y396492D01*
X325466Y396506D01*
X325355Y396645D01*
X325244Y396784D01*
X325077Y397075D01*
X324966Y397366D01*
X324883Y397643D01*
X324828Y397879D01*
X324814Y397976D01*
Y398073D01*
X324800Y398143D01*
Y398198D01*
Y398226D01*
Y398240D01*
X324814Y398531D01*
X324855Y398795D01*
X324925Y399044D01*
X324994Y399252D01*
X325077Y399432D01*
X325133Y399571D01*
X325188Y399654D01*
X325202Y399668D01*
Y399682D01*
X325368Y399904D01*
X325535Y400098D01*
X325715Y400265D01*
X325882Y400389D01*
X326034Y400486D01*
X326159Y400542D01*
X326242Y400583D01*
X326256Y400597D01*
X326270D01*
X326395Y400639D01*
X326547Y400681D01*
X326852Y400750D01*
X327185Y400792D01*
X327490Y400833D01*
X327782Y400847D01*
X327906D01*
X328017Y400861D01*
X332469D01*
Y391264D01*
D02*
G37*
G36*
X352397Y367889D02*
X352632Y367875D01*
X352854Y367833D01*
X353062Y367791D01*
X353257Y367736D01*
X353437Y367681D01*
X353603Y367611D01*
X353756Y367542D01*
X353895Y367473D01*
X354006Y367403D01*
X354103Y367348D01*
X354186Y367292D01*
X354255Y367251D01*
X354297Y367209D01*
X354324Y367195D01*
X354338Y367181D01*
X354477Y367043D01*
X354602Y366890D01*
X354727Y366724D01*
X354824Y366557D01*
X354990Y366224D01*
X355101Y365892D01*
X355143Y365739D01*
X355184Y365587D01*
X355212Y365462D01*
X355240Y365351D01*
X355254Y365254D01*
Y365184D01*
X355267Y365143D01*
Y365129D01*
X354061Y365004D01*
X354033Y365323D01*
X353978Y365600D01*
X353895Y365850D01*
X353797Y366044D01*
X353714Y366211D01*
X353631Y366321D01*
X353576Y366391D01*
X353548Y366419D01*
X353340Y366585D01*
X353118Y366710D01*
X352882Y366807D01*
X352674Y366862D01*
X352480Y366904D01*
X352313Y366918D01*
X352258Y366932D01*
X352175D01*
X351884Y366918D01*
X351620Y366862D01*
X351398Y366779D01*
X351204Y366696D01*
X351051Y366599D01*
X350954Y366530D01*
X350885Y366474D01*
X350857Y366446D01*
X350691Y366252D01*
X350566Y366058D01*
X350469Y365864D01*
X350414Y365670D01*
X350372Y365517D01*
X350358Y365378D01*
X350344Y365295D01*
Y365281D01*
Y365267D01*
X350372Y365018D01*
X350427Y364754D01*
X350524Y364519D01*
X350622Y364297D01*
X350732Y364116D01*
X350830Y363964D01*
X350857Y363908D01*
X350885Y363867D01*
X350913Y363853D01*
Y363839D01*
X351024Y363686D01*
X351162Y363534D01*
X351315Y363368D01*
X351481Y363201D01*
X351828Y362868D01*
X352175Y362535D01*
X352355Y362383D01*
X352508Y362244D01*
X352660Y362119D01*
X352785Y362008D01*
X352882Y361925D01*
X352965Y361856D01*
X353021Y361814D01*
X353035Y361800D01*
X353381Y361509D01*
X353700Y361232D01*
X353964Y360982D01*
X354172Y360774D01*
X354352Y360594D01*
X354477Y360469D01*
X354546Y360386D01*
X354574Y360372D01*
Y360358D01*
X354768Y360122D01*
X354921Y359900D01*
X355060Y359678D01*
X355170Y359484D01*
X355254Y359318D01*
X355309Y359193D01*
X355337Y359110D01*
X355351Y359096D01*
Y359082D01*
X355406Y358930D01*
X355434Y358791D01*
X355462Y358652D01*
X355476Y358527D01*
X355489Y358416D01*
Y358333D01*
Y358278D01*
Y358264D01*
X349124D01*
Y359401D01*
X353853D01*
X353686Y359637D01*
X353603Y359734D01*
X353534Y359831D01*
X353465Y359914D01*
X353409Y359970D01*
X353368Y360011D01*
X353354Y360025D01*
X353284Y360095D01*
X353201Y360164D01*
X353007Y360344D01*
X352785Y360552D01*
X352549Y360760D01*
X352327Y360941D01*
X352230Y361024D01*
X352147Y361107D01*
X352078Y361162D01*
X352022Y361204D01*
X351995Y361232D01*
X351981Y361246D01*
X351759Y361440D01*
X351537Y361620D01*
X351343Y361800D01*
X351162Y361953D01*
X350996Y362105D01*
X350857Y362244D01*
X350719Y362369D01*
X350608Y362480D01*
X350497Y362591D01*
X350414Y362674D01*
X350344Y362743D01*
X350275Y362813D01*
X350205Y362896D01*
X350178Y362924D01*
X349984Y363159D01*
X349817Y363368D01*
X349678Y363576D01*
X349568Y363742D01*
X349484Y363895D01*
X349429Y364006D01*
X349401Y364075D01*
X349387Y364103D01*
X349304Y364311D01*
X349249Y364519D01*
X349193Y364713D01*
X349165Y364879D01*
X349151Y365032D01*
X349138Y365143D01*
Y365212D01*
Y365240D01*
X349151Y365448D01*
X349179Y365642D01*
X349207Y365836D01*
X349263Y366003D01*
X349401Y366335D01*
X349540Y366599D01*
X349623Y366724D01*
X349692Y366821D01*
X349762Y366918D01*
X349831Y366987D01*
X349887Y367043D01*
X349914Y367098D01*
X349942Y367112D01*
X349956Y367126D01*
X350108Y367265D01*
X350275Y367389D01*
X350455Y367486D01*
X350635Y367570D01*
X350996Y367708D01*
X351357Y367805D01*
X351509Y367833D01*
X351662Y367861D01*
X351800Y367875D01*
X351911Y367889D01*
X352008Y367902D01*
X352147D01*
X352397Y367889D01*
D02*
G37*
G36*
X347654Y362799D02*
X346544Y362646D01*
X346447Y362799D01*
X346322Y362924D01*
X346211Y363049D01*
X346101Y363146D01*
X345989Y363215D01*
X345906Y363284D01*
X345851Y363312D01*
X345837Y363326D01*
X345657Y363409D01*
X345476Y363479D01*
X345310Y363520D01*
X345144Y363562D01*
X345005Y363576D01*
X344894Y363589D01*
X344630D01*
X344464Y363562D01*
X344173Y363492D01*
X343923Y363395D01*
X343701Y363298D01*
X343535Y363187D01*
X343410Y363090D01*
X343341Y363021D01*
X343313Y363007D01*
Y362993D01*
X343119Y362757D01*
X342980Y362508D01*
X342883Y362244D01*
X342814Y361981D01*
X342772Y361759D01*
X342758Y361662D01*
Y361578D01*
X342744Y361509D01*
Y361454D01*
Y361426D01*
Y361412D01*
Y361218D01*
X342772Y361038D01*
X342841Y360691D01*
X342938Y360400D01*
X343036Y360164D01*
X343147Y359970D01*
X343244Y359817D01*
X343285Y359776D01*
X343313Y359734D01*
X343327Y359720D01*
X343341Y359706D01*
X343452Y359595D01*
X343563Y359498D01*
X343812Y359332D01*
X344048Y359221D01*
X344284Y359151D01*
X344478Y359096D01*
X344644Y359082D01*
X344700Y359068D01*
X344783D01*
X345047Y359082D01*
X345282Y359138D01*
X345490Y359207D01*
X345657Y359290D01*
X345809Y359373D01*
X345920Y359443D01*
X345976Y359498D01*
X346003Y359512D01*
X346170Y359706D01*
X346309Y359914D01*
X346419Y360150D01*
X346503Y360358D01*
X346558Y360566D01*
X346600Y360719D01*
X346614Y360788D01*
X346628Y360830D01*
Y360857D01*
Y360871D01*
X347862Y360774D01*
X347834Y360552D01*
X347792Y360344D01*
X347668Y359956D01*
X347515Y359623D01*
X347432Y359470D01*
X347349Y359346D01*
X347279Y359221D01*
X347196Y359110D01*
X347127Y359027D01*
X347057Y358957D01*
X347002Y358902D01*
X346974Y358846D01*
X346946Y358833D01*
X346933Y358819D01*
X346766Y358694D01*
X346600Y358583D01*
X346419Y358486D01*
X346239Y358403D01*
X345892Y358278D01*
X345546Y358195D01*
X345393Y358153D01*
X345241Y358139D01*
X345116Y358125D01*
X345005Y358111D01*
X344908Y358097D01*
X344783D01*
X344492Y358111D01*
X344214Y358153D01*
X343951Y358209D01*
X343715Y358278D01*
X343493Y358375D01*
X343285Y358472D01*
X343091Y358569D01*
X342925Y358680D01*
X342772Y358791D01*
X342633Y358888D01*
X342522Y358999D01*
X342425Y359082D01*
X342356Y359151D01*
X342300Y359207D01*
X342273Y359249D01*
X342259Y359263D01*
X342120Y359443D01*
X342009Y359637D01*
X341898Y359817D01*
X341815Y360011D01*
X341676Y360386D01*
X341593Y360746D01*
X341566Y360899D01*
X341538Y361051D01*
X341524Y361176D01*
X341510Y361287D01*
X341496Y361384D01*
Y361454D01*
Y361495D01*
Y361509D01*
X341510Y361759D01*
X341538Y361995D01*
X341579Y362230D01*
X341635Y362438D01*
X341704Y362632D01*
X341773Y362827D01*
X341857Y362993D01*
X341926Y363146D01*
X342009Y363284D01*
X342093Y363409D01*
X342162Y363506D01*
X342231Y363603D01*
X342287Y363673D01*
X342328Y363714D01*
X342356Y363742D01*
X342370Y363756D01*
X342536Y363908D01*
X342703Y364047D01*
X342883Y364158D01*
X343063Y364255D01*
X343244Y364352D01*
X343424Y364422D01*
X343757Y364519D01*
X343909Y364560D01*
X344048Y364588D01*
X344173Y364602D01*
X344284Y364616D01*
X344367Y364630D01*
X344672D01*
X344838Y364602D01*
X345171Y364533D01*
X345476Y364435D01*
X345754Y364324D01*
X345976Y364213D01*
X346073Y364158D01*
X346156Y364116D01*
X346225Y364075D01*
X346267Y364047D01*
X346295Y364033D01*
X346309Y364019D01*
X345795Y366613D01*
X341954D01*
Y367736D01*
X346725D01*
X347654Y362799D01*
D02*
G37*
G36*
X364504Y358264D02*
X363228D01*
Y362522D01*
X361591D01*
X361439Y362508D01*
X361328D01*
X361231Y362494D01*
X361162Y362480D01*
X361106D01*
X361078Y362466D01*
X361064D01*
X360843Y362397D01*
X360746Y362355D01*
X360662Y362313D01*
X360579Y362272D01*
X360524Y362244D01*
X360496Y362230D01*
X360482Y362216D01*
X360371Y362133D01*
X360260Y362036D01*
X360052Y361828D01*
X359955Y361731D01*
X359886Y361648D01*
X359844Y361592D01*
X359830Y361578D01*
X359692Y361384D01*
X359539Y361176D01*
X359386Y360954D01*
X359234Y360746D01*
X359109Y360552D01*
X359012Y360400D01*
X358970Y360344D01*
X358943Y360303D01*
X358915Y360275D01*
Y360261D01*
X357653Y358264D01*
X356072D01*
X357722Y360871D01*
X357916Y361149D01*
X358097Y361398D01*
X358277Y361606D01*
X358429Y361800D01*
X358568Y361939D01*
X358679Y362050D01*
X358749Y362119D01*
X358776Y362147D01*
X358887Y362230D01*
X359012Y362327D01*
X359262Y362480D01*
X359372Y362535D01*
X359456Y362591D01*
X359511Y362619D01*
X359539Y362632D01*
X359289Y362674D01*
X359054Y362716D01*
X358845Y362785D01*
X358638Y362840D01*
X358457Y362910D01*
X358291Y362993D01*
X358138Y363062D01*
X358000Y363132D01*
X357889Y363215D01*
X357778Y363284D01*
X357695Y363340D01*
X357625Y363395D01*
X357570Y363437D01*
X357528Y363479D01*
X357514Y363492D01*
X357500Y363506D01*
X357389Y363645D01*
X357278Y363784D01*
X357112Y364075D01*
X357001Y364366D01*
X356918Y364643D01*
X356862Y364879D01*
X356848Y364976D01*
Y365073D01*
X356835Y365143D01*
Y365198D01*
Y365226D01*
Y365240D01*
X356848Y365531D01*
X356890Y365794D01*
X356959Y366044D01*
X357029Y366252D01*
X357112Y366432D01*
X357168Y366571D01*
X357223Y366654D01*
X357237Y366668D01*
Y366682D01*
X357403Y366904D01*
X357570Y367098D01*
X357750Y367265D01*
X357916Y367389D01*
X358069Y367486D01*
X358194Y367542D01*
X358277Y367584D01*
X358291Y367597D01*
X358305D01*
X358429Y367639D01*
X358582Y367681D01*
X358887Y367750D01*
X359220Y367791D01*
X359525Y367833D01*
X359816Y367847D01*
X359941D01*
X360052Y367861D01*
X364504D01*
Y358264D01*
D02*
G37*
G36*
X352091Y332305D02*
X352327Y332291D01*
X352549Y332250D01*
X352757Y332208D01*
X352951Y332153D01*
X353131Y332097D01*
X353298Y332028D01*
X353450Y331959D01*
X353589Y331889D01*
X353700Y331820D01*
X353797Y331764D01*
X353880Y331709D01*
X353950Y331668D01*
X353991Y331626D01*
X354019Y331612D01*
X354033Y331598D01*
X354171Y331459D01*
X354296Y331307D01*
X354421Y331141D01*
X354518Y330974D01*
X354685Y330641D01*
X354796Y330308D01*
X354837Y330156D01*
X354879Y330003D01*
X354907Y329878D01*
X354934Y329767D01*
X354948Y329670D01*
Y329601D01*
X354962Y329560D01*
Y329546D01*
X353755Y329421D01*
X353728Y329740D01*
X353672Y330017D01*
X353589Y330267D01*
X353492Y330461D01*
X353409Y330627D01*
X353326Y330738D01*
X353270Y330808D01*
X353242Y330835D01*
X353034Y331002D01*
X352812Y331127D01*
X352577Y331224D01*
X352369Y331279D01*
X352174Y331321D01*
X352008Y331335D01*
X351953Y331348D01*
X351869D01*
X351578Y331335D01*
X351315Y331279D01*
X351093Y331196D01*
X350899Y331113D01*
X350746Y331016D01*
X350649Y330946D01*
X350580Y330891D01*
X350552Y330863D01*
X350385Y330669D01*
X350261Y330475D01*
X350163Y330281D01*
X350108Y330087D01*
X350066Y329934D01*
X350053Y329795D01*
X350039Y329712D01*
Y329698D01*
Y329684D01*
X350066Y329435D01*
X350122Y329171D01*
X350219Y328935D01*
X350316Y328713D01*
X350427Y328533D01*
X350524Y328381D01*
X350552Y328325D01*
X350580Y328284D01*
X350607Y328270D01*
Y328256D01*
X350718Y328103D01*
X350857Y327951D01*
X351009Y327784D01*
X351176Y327618D01*
X351523Y327285D01*
X351869Y326952D01*
X352050Y326800D01*
X352202Y326661D01*
X352355Y326536D01*
X352480Y326425D01*
X352577Y326342D01*
X352660Y326273D01*
X352715Y326231D01*
X352729Y326217D01*
X353076Y325926D01*
X353395Y325649D01*
X353658Y325399D01*
X353866Y325191D01*
X354047Y325011D01*
X354171Y324886D01*
X354241Y324803D01*
X354269Y324789D01*
Y324775D01*
X354463Y324539D01*
X354615Y324317D01*
X354754Y324095D01*
X354865Y323901D01*
X354948Y323735D01*
X355004Y323610D01*
X355031Y323527D01*
X355045Y323513D01*
Y323499D01*
X355101Y323346D01*
X355128Y323208D01*
X355156Y323069D01*
X355170Y322944D01*
X355184Y322833D01*
Y322750D01*
Y322695D01*
Y322681D01*
X348818D01*
Y323818D01*
X353547D01*
X353381Y324054D01*
X353298Y324151D01*
X353228Y324248D01*
X353159Y324331D01*
X353104Y324386D01*
X353062Y324428D01*
X353048Y324442D01*
X352979Y324511D01*
X352896Y324581D01*
X352701Y324761D01*
X352480Y324969D01*
X352244Y325177D01*
X352022Y325357D01*
X351925Y325440D01*
X351842Y325524D01*
X351772Y325579D01*
X351717Y325621D01*
X351689Y325649D01*
X351675Y325662D01*
X351453Y325857D01*
X351231Y326037D01*
X351037Y326217D01*
X350857Y326370D01*
X350690Y326522D01*
X350552Y326661D01*
X350413Y326786D01*
X350302Y326897D01*
X350191Y327008D01*
X350108Y327091D01*
X350039Y327160D01*
X349969Y327230D01*
X349900Y327313D01*
X349872Y327341D01*
X349678Y327576D01*
X349512Y327784D01*
X349373Y327992D01*
X349262Y328159D01*
X349179Y328311D01*
X349123Y328422D01*
X349096Y328492D01*
X349082Y328519D01*
X348999Y328727D01*
X348943Y328935D01*
X348888Y329129D01*
X348860Y329296D01*
X348846Y329449D01*
X348832Y329560D01*
Y329629D01*
Y329656D01*
X348846Y329865D01*
X348874Y330059D01*
X348901Y330253D01*
X348957Y330419D01*
X349096Y330752D01*
X349234Y331016D01*
X349318Y331141D01*
X349387Y331237D01*
X349456Y331335D01*
X349526Y331404D01*
X349581Y331459D01*
X349609Y331515D01*
X349636Y331529D01*
X349650Y331543D01*
X349803Y331681D01*
X349969Y331806D01*
X350150Y331903D01*
X350330Y331986D01*
X350690Y332125D01*
X351051Y332222D01*
X351204Y332250D01*
X351356Y332278D01*
X351495Y332291D01*
X351606Y332305D01*
X351703Y332319D01*
X351842D01*
X352091Y332305D01*
D02*
G37*
G36*
X364198Y322681D02*
X362923D01*
Y326938D01*
X361286D01*
X361133Y326925D01*
X361022D01*
X360925Y326911D01*
X360856Y326897D01*
X360801D01*
X360773Y326883D01*
X360759D01*
X360537Y326814D01*
X360440Y326772D01*
X360357Y326730D01*
X360274Y326689D01*
X360218Y326661D01*
X360190Y326647D01*
X360177Y326633D01*
X360066Y326550D01*
X359955Y326453D01*
X359747Y326245D01*
X359650Y326148D01*
X359580Y326065D01*
X359539Y326009D01*
X359525Y325995D01*
X359386Y325801D01*
X359234Y325593D01*
X359081Y325371D01*
X358928Y325163D01*
X358803Y324969D01*
X358707Y324817D01*
X358665Y324761D01*
X358637Y324719D01*
X358609Y324692D01*
Y324678D01*
X357347Y322681D01*
X355766D01*
X357417Y325288D01*
X357611Y325565D01*
X357791Y325815D01*
X357971Y326023D01*
X358124Y326217D01*
X358263Y326356D01*
X358374Y326467D01*
X358443Y326536D01*
X358471Y326564D01*
X358582Y326647D01*
X358707Y326744D01*
X358956Y326897D01*
X359067Y326952D01*
X359150Y327008D01*
X359206Y327035D01*
X359234Y327049D01*
X358984Y327091D01*
X358748Y327132D01*
X358540Y327202D01*
X358332Y327257D01*
X358152Y327327D01*
X357985Y327410D01*
X357833Y327479D01*
X357694Y327548D01*
X357583Y327632D01*
X357472Y327701D01*
X357389Y327757D01*
X357320Y327812D01*
X357264Y327854D01*
X357223Y327895D01*
X357209Y327909D01*
X357195Y327923D01*
X357084Y328062D01*
X356973Y328200D01*
X356806Y328492D01*
X356696Y328783D01*
X356612Y329060D01*
X356557Y329296D01*
X356543Y329393D01*
Y329490D01*
X356529Y329560D01*
Y329615D01*
Y329643D01*
Y329656D01*
X356543Y329948D01*
X356585Y330211D01*
X356654Y330461D01*
X356723Y330669D01*
X356806Y330849D01*
X356862Y330988D01*
X356917Y331071D01*
X356931Y331085D01*
Y331099D01*
X357098Y331321D01*
X357264Y331515D01*
X357444Y331681D01*
X357611Y331806D01*
X357763Y331903D01*
X357888Y331959D01*
X357971Y332000D01*
X357985Y332014D01*
X357999D01*
X358124Y332056D01*
X358277Y332097D01*
X358582Y332167D01*
X358914Y332208D01*
X359220Y332250D01*
X359511Y332264D01*
X359636D01*
X359747Y332278D01*
X364198D01*
Y322681D01*
D02*
G37*
G36*
X347958Y326065D02*
Y324983D01*
X343784D01*
Y322681D01*
X342605D01*
Y324983D01*
X341302D01*
Y326065D01*
X342605D01*
Y332278D01*
X343562D01*
X347958Y326065D01*
D02*
G37*
G36*
X347313Y400305D02*
X347549Y400291D01*
X347771Y400250D01*
X347979Y400208D01*
X348173Y400153D01*
X348354Y400097D01*
X348520Y400028D01*
X348673Y399959D01*
X348811Y399889D01*
X348922Y399820D01*
X349019Y399765D01*
X349103Y399709D01*
X349172Y399668D01*
X349213Y399626D01*
X349241Y399612D01*
X349255Y399598D01*
X349394Y399459D01*
X349519Y399307D01*
X349643Y399141D01*
X349740Y398974D01*
X349907Y398641D01*
X350018Y398308D01*
X350059Y398156D01*
X350101Y398003D01*
X350129Y397878D01*
X350157Y397767D01*
X350170Y397670D01*
Y397601D01*
X350184Y397560D01*
Y397546D01*
X348978Y397421D01*
X348950Y397740D01*
X348895Y398017D01*
X348811Y398267D01*
X348714Y398461D01*
X348631Y398627D01*
X348548Y398738D01*
X348492Y398808D01*
X348465Y398835D01*
X348257Y399002D01*
X348035Y399127D01*
X347799Y399224D01*
X347591Y399279D01*
X347397Y399321D01*
X347230Y399335D01*
X347175Y399348D01*
X347092D01*
X346800Y399335D01*
X346537Y399279D01*
X346315Y399196D01*
X346121Y399113D01*
X345968Y399016D01*
X345871Y398946D01*
X345802Y398891D01*
X345774Y398863D01*
X345608Y398669D01*
X345483Y398475D01*
X345386Y398281D01*
X345330Y398087D01*
X345289Y397934D01*
X345275Y397795D01*
X345261Y397712D01*
Y397698D01*
Y397684D01*
X345289Y397435D01*
X345344Y397171D01*
X345441Y396935D01*
X345538Y396713D01*
X345649Y396533D01*
X345746Y396381D01*
X345774Y396325D01*
X345802Y396284D01*
X345830Y396270D01*
Y396256D01*
X345941Y396103D01*
X346079Y395951D01*
X346232Y395784D01*
X346398Y395618D01*
X346745Y395285D01*
X347092Y394952D01*
X347272Y394800D01*
X347425Y394661D01*
X347577Y394536D01*
X347702Y394425D01*
X347799Y394342D01*
X347882Y394273D01*
X347938Y394231D01*
X347952Y394217D01*
X348298Y393926D01*
X348617Y393649D01*
X348881Y393399D01*
X349089Y393191D01*
X349269Y393011D01*
X349394Y392886D01*
X349463Y392803D01*
X349491Y392789D01*
Y392775D01*
X349685Y392539D01*
X349838Y392317D01*
X349976Y392095D01*
X350087Y391901D01*
X350170Y391735D01*
X350226Y391610D01*
X350254Y391527D01*
X350267Y391513D01*
Y391499D01*
X350323Y391346D01*
X350351Y391208D01*
X350378Y391069D01*
X350392Y390944D01*
X350406Y390833D01*
Y390750D01*
Y390695D01*
Y390681D01*
X344041D01*
Y391818D01*
X348770D01*
X348603Y392054D01*
X348520Y392151D01*
X348451Y392248D01*
X348381Y392331D01*
X348326Y392387D01*
X348284Y392428D01*
X348270Y392442D01*
X348201Y392511D01*
X348118Y392581D01*
X347924Y392761D01*
X347702Y392969D01*
X347466Y393177D01*
X347244Y393357D01*
X347147Y393441D01*
X347064Y393524D01*
X346995Y393579D01*
X346939Y393621D01*
X346911Y393649D01*
X346898Y393662D01*
X346676Y393857D01*
X346454Y394037D01*
X346259Y394217D01*
X346079Y394370D01*
X345913Y394522D01*
X345774Y394661D01*
X345635Y394786D01*
X345524Y394897D01*
X345414Y395008D01*
X345330Y395091D01*
X345261Y395160D01*
X345192Y395230D01*
X345122Y395313D01*
X345095Y395340D01*
X344900Y395576D01*
X344734Y395784D01*
X344595Y395992D01*
X344484Y396159D01*
X344401Y396311D01*
X344346Y396422D01*
X344318Y396492D01*
X344304Y396519D01*
X344221Y396727D01*
X344165Y396935D01*
X344110Y397130D01*
X344082Y397296D01*
X344068Y397449D01*
X344054Y397560D01*
Y397629D01*
Y397657D01*
X344068Y397865D01*
X344096Y398059D01*
X344124Y398253D01*
X344179Y398419D01*
X344318Y398752D01*
X344457Y399016D01*
X344540Y399141D01*
X344609Y399238D01*
X344678Y399335D01*
X344748Y399404D01*
X344803Y399459D01*
X344831Y399515D01*
X344859Y399529D01*
X344873Y399543D01*
X345025Y399681D01*
X345192Y399806D01*
X345372Y399903D01*
X345552Y399986D01*
X345913Y400125D01*
X346273Y400222D01*
X346426Y400250D01*
X346578Y400278D01*
X346717Y400291D01*
X346828Y400305D01*
X346925Y400319D01*
X347064D01*
X347313Y400305D01*
D02*
G37*
G36*
X339852D02*
X340088Y400291D01*
X340310Y400250D01*
X340518Y400208D01*
X340712Y400153D01*
X340892Y400097D01*
X341059Y400028D01*
X341211Y399959D01*
X341350Y399889D01*
X341461Y399820D01*
X341558Y399765D01*
X341641Y399709D01*
X341711Y399668D01*
X341752Y399626D01*
X341780Y399612D01*
X341794Y399598D01*
X341933Y399459D01*
X342057Y399307D01*
X342182Y399141D01*
X342279Y398974D01*
X342446Y398641D01*
X342557Y398308D01*
X342598Y398156D01*
X342640Y398003D01*
X342668Y397878D01*
X342695Y397767D01*
X342709Y397670D01*
Y397601D01*
X342723Y397560D01*
Y397546D01*
X341516Y397421D01*
X341489Y397740D01*
X341433Y398017D01*
X341350Y398267D01*
X341253Y398461D01*
X341170Y398627D01*
X341087Y398738D01*
X341031Y398808D01*
X341003Y398835D01*
X340795Y399002D01*
X340574Y399127D01*
X340338Y399224D01*
X340130Y399279D01*
X339935Y399321D01*
X339769Y399335D01*
X339714Y399348D01*
X339630D01*
X339339Y399335D01*
X339076Y399279D01*
X338854Y399196D01*
X338660Y399113D01*
X338507Y399016D01*
X338410Y398946D01*
X338341Y398891D01*
X338313Y398863D01*
X338147Y398669D01*
X338022Y398475D01*
X337925Y398281D01*
X337869Y398087D01*
X337827Y397934D01*
X337814Y397795D01*
X337800Y397712D01*
Y397698D01*
Y397684D01*
X337827Y397435D01*
X337883Y397171D01*
X337980Y396935D01*
X338077Y396713D01*
X338188Y396533D01*
X338285Y396381D01*
X338313Y396325D01*
X338341Y396284D01*
X338368Y396270D01*
Y396256D01*
X338479Y396103D01*
X338618Y395951D01*
X338771Y395784D01*
X338937Y395618D01*
X339284Y395285D01*
X339630Y394952D01*
X339811Y394800D01*
X339963Y394661D01*
X340116Y394536D01*
X340241Y394425D01*
X340338Y394342D01*
X340421Y394273D01*
X340476Y394231D01*
X340490Y394217D01*
X340837Y393926D01*
X341156Y393649D01*
X341419Y393399D01*
X341628Y393191D01*
X341808Y393011D01*
X341933Y392886D01*
X342002Y392803D01*
X342030Y392789D01*
Y392775D01*
X342224Y392539D01*
X342376Y392317D01*
X342515Y392095D01*
X342626Y391901D01*
X342709Y391735D01*
X342765Y391610D01*
X342792Y391527D01*
X342806Y391513D01*
Y391499D01*
X342862Y391346D01*
X342890Y391208D01*
X342917Y391069D01*
X342931Y390944D01*
X342945Y390833D01*
Y390750D01*
Y390695D01*
Y390681D01*
X336579D01*
Y391818D01*
X341309D01*
X341142Y392054D01*
X341059Y392151D01*
X340989Y392248D01*
X340920Y392331D01*
X340865Y392387D01*
X340823Y392428D01*
X340809Y392442D01*
X340740Y392511D01*
X340657Y392581D01*
X340462Y392761D01*
X340241Y392969D01*
X340005Y393177D01*
X339783Y393357D01*
X339686Y393441D01*
X339603Y393524D01*
X339533Y393579D01*
X339478Y393621D01*
X339450Y393649D01*
X339436Y393662D01*
X339214Y393857D01*
X338993Y394037D01*
X338798Y394217D01*
X338618Y394370D01*
X338452Y394522D01*
X338313Y394661D01*
X338174Y394786D01*
X338063Y394897D01*
X337952Y395008D01*
X337869Y395091D01*
X337800Y395160D01*
X337730Y395230D01*
X337661Y395313D01*
X337633Y395340D01*
X337439Y395576D01*
X337273Y395784D01*
X337134Y395992D01*
X337023Y396159D01*
X336940Y396311D01*
X336884Y396422D01*
X336857Y396492D01*
X336843Y396519D01*
X336760Y396727D01*
X336704Y396935D01*
X336649Y397130D01*
X336621Y397296D01*
X336607Y397449D01*
X336593Y397560D01*
Y397629D01*
Y397657D01*
X336607Y397865D01*
X336635Y398059D01*
X336663Y398253D01*
X336718Y398419D01*
X336857Y398752D01*
X336995Y399016D01*
X337079Y399141D01*
X337148Y399238D01*
X337217Y399335D01*
X337287Y399404D01*
X337342Y399459D01*
X337370Y399515D01*
X337398Y399529D01*
X337411Y399543D01*
X337564Y399681D01*
X337730Y399806D01*
X337911Y399903D01*
X338091Y399986D01*
X338452Y400125D01*
X338812Y400222D01*
X338965Y400250D01*
X339117Y400278D01*
X339256Y400291D01*
X339367Y400305D01*
X339464Y400319D01*
X339603D01*
X339852Y400305D01*
D02*
G37*
G36*
X359421Y390681D02*
X358145D01*
Y394938D01*
X356508D01*
X356356Y394925D01*
X356245D01*
X356148Y394911D01*
X356078Y394897D01*
X356023D01*
X355995Y394883D01*
X355981D01*
X355759Y394813D01*
X355662Y394772D01*
X355579Y394730D01*
X355496Y394689D01*
X355440Y394661D01*
X355413Y394647D01*
X355399Y394633D01*
X355288Y394550D01*
X355177Y394453D01*
X354969Y394245D01*
X354872Y394148D01*
X354802Y394065D01*
X354761Y394009D01*
X354747Y393995D01*
X354608Y393801D01*
X354456Y393593D01*
X354303Y393371D01*
X354151Y393163D01*
X354026Y392969D01*
X353929Y392817D01*
X353887Y392761D01*
X353859Y392719D01*
X353832Y392692D01*
Y392678D01*
X352570Y390681D01*
X350989D01*
X352639Y393288D01*
X352833Y393565D01*
X353013Y393815D01*
X353194Y394023D01*
X353346Y394217D01*
X353485Y394356D01*
X353596Y394467D01*
X353665Y394536D01*
X353693Y394564D01*
X353804Y394647D01*
X353929Y394744D01*
X354178Y394897D01*
X354289Y394952D01*
X354372Y395008D01*
X354428Y395035D01*
X354456Y395049D01*
X354206Y395091D01*
X353970Y395132D01*
X353762Y395202D01*
X353554Y395257D01*
X353374Y395327D01*
X353208Y395410D01*
X353055Y395479D01*
X352916Y395549D01*
X352805Y395632D01*
X352694Y395701D01*
X352611Y395757D01*
X352542Y395812D01*
X352486Y395854D01*
X352445Y395895D01*
X352431Y395909D01*
X352417Y395923D01*
X352306Y396062D01*
X352195Y396200D01*
X352029Y396492D01*
X351918Y396783D01*
X351835Y397060D01*
X351779Y397296D01*
X351765Y397393D01*
Y397490D01*
X351751Y397560D01*
Y397615D01*
Y397643D01*
Y397657D01*
X351765Y397948D01*
X351807Y398211D01*
X351876Y398461D01*
X351945Y398669D01*
X352029Y398849D01*
X352084Y398988D01*
X352140Y399071D01*
X352154Y399085D01*
Y399099D01*
X352320Y399321D01*
X352486Y399515D01*
X352667Y399681D01*
X352833Y399806D01*
X352986Y399903D01*
X353111Y399959D01*
X353194Y400000D01*
X353208Y400014D01*
X353221D01*
X353346Y400056D01*
X353499Y400097D01*
X353804Y400167D01*
X354137Y400208D01*
X354442Y400250D01*
X354733Y400264D01*
X354858D01*
X354969Y400278D01*
X359421D01*
Y390681D01*
D02*
G37*
G36*
X351933Y355805D02*
X352169Y355792D01*
X352391Y355750D01*
X352599Y355708D01*
X352793Y355653D01*
X352973Y355597D01*
X353139Y355528D01*
X353292Y355459D01*
X353431Y355389D01*
X353542Y355320D01*
X353639Y355265D01*
X353722Y355209D01*
X353791Y355168D01*
X353833Y355126D01*
X353861Y355112D01*
X353875Y355098D01*
X354013Y354959D01*
X354138Y354807D01*
X354263Y354641D01*
X354360Y354474D01*
X354526Y354141D01*
X354637Y353808D01*
X354679Y353656D01*
X354720Y353503D01*
X354748Y353378D01*
X354776Y353268D01*
X354790Y353170D01*
Y353101D01*
X354804Y353060D01*
Y353046D01*
X353597Y352921D01*
X353569Y353240D01*
X353514Y353517D01*
X353431Y353767D01*
X353334Y353961D01*
X353250Y354127D01*
X353167Y354238D01*
X353112Y354308D01*
X353084Y354335D01*
X352876Y354502D01*
X352654Y354627D01*
X352418Y354724D01*
X352210Y354779D01*
X352016Y354821D01*
X351850Y354835D01*
X351794Y354849D01*
X351711D01*
X351420Y354835D01*
X351156Y354779D01*
X350934Y354696D01*
X350740Y354613D01*
X350588Y354516D01*
X350491Y354446D01*
X350421Y354391D01*
X350393Y354363D01*
X350227Y354169D01*
X350102Y353975D01*
X350005Y353781D01*
X349950Y353587D01*
X349908Y353434D01*
X349894Y353295D01*
X349880Y353212D01*
Y353198D01*
Y353184D01*
X349908Y352935D01*
X349964Y352671D01*
X350061Y352435D01*
X350158Y352214D01*
X350269Y352033D01*
X350366Y351881D01*
X350393Y351825D01*
X350421Y351784D01*
X350449Y351770D01*
Y351756D01*
X350560Y351603D01*
X350699Y351451D01*
X350851Y351284D01*
X351018Y351118D01*
X351364Y350785D01*
X351711Y350452D01*
X351891Y350300D01*
X352044Y350161D01*
X352196Y350036D01*
X352321Y349925D01*
X352418Y349842D01*
X352501Y349773D01*
X352557Y349731D01*
X352571Y349717D01*
X352918Y349426D01*
X353237Y349149D01*
X353500Y348899D01*
X353708Y348691D01*
X353888Y348511D01*
X354013Y348386D01*
X354082Y348303D01*
X354110Y348289D01*
Y348275D01*
X354304Y348039D01*
X354457Y347817D01*
X354596Y347595D01*
X354707Y347401D01*
X354790Y347235D01*
X354845Y347110D01*
X354873Y347027D01*
X354887Y347013D01*
Y346999D01*
X354942Y346846D01*
X354970Y346708D01*
X354998Y346569D01*
X355012Y346444D01*
X355025Y346333D01*
Y346250D01*
Y346195D01*
Y346181D01*
X348660D01*
Y347318D01*
X353389D01*
X353223Y347554D01*
X353139Y347651D01*
X353070Y347748D01*
X353001Y347831D01*
X352945Y347887D01*
X352904Y347928D01*
X352890Y347942D01*
X352821Y348011D01*
X352737Y348081D01*
X352543Y348261D01*
X352321Y348469D01*
X352085Y348677D01*
X351864Y348857D01*
X351767Y348941D01*
X351683Y349024D01*
X351614Y349079D01*
X351558Y349121D01*
X351531Y349149D01*
X351517Y349162D01*
X351295Y349357D01*
X351073Y349537D01*
X350879Y349717D01*
X350699Y349870D01*
X350532Y350022D01*
X350393Y350161D01*
X350255Y350286D01*
X350144Y350397D01*
X350033Y350508D01*
X349950Y350591D01*
X349880Y350660D01*
X349811Y350730D01*
X349742Y350813D01*
X349714Y350840D01*
X349520Y351076D01*
X349353Y351284D01*
X349215Y351492D01*
X349104Y351659D01*
X349021Y351811D01*
X348965Y351922D01*
X348937Y351992D01*
X348923Y352019D01*
X348840Y352227D01*
X348785Y352435D01*
X348729Y352630D01*
X348702Y352796D01*
X348688Y352948D01*
X348674Y353060D01*
Y353129D01*
Y353157D01*
X348688Y353365D01*
X348715Y353559D01*
X348743Y353753D01*
X348799Y353919D01*
X348937Y354252D01*
X349076Y354516D01*
X349159Y354641D01*
X349229Y354738D01*
X349298Y354835D01*
X349367Y354904D01*
X349423Y354959D01*
X349450Y355015D01*
X349478Y355029D01*
X349492Y355043D01*
X349645Y355181D01*
X349811Y355306D01*
X349991Y355403D01*
X350172Y355486D01*
X350532Y355625D01*
X350893Y355722D01*
X351045Y355750D01*
X351198Y355778D01*
X351337Y355792D01*
X351447Y355805D01*
X351545Y355819D01*
X351683D01*
X351933Y355805D01*
D02*
G37*
G36*
X343862Y355583D02*
X344014Y355362D01*
X344194Y355140D01*
X344361Y354946D01*
X344527Y354779D01*
X344652Y354641D01*
X344707Y354599D01*
X344749Y354557D01*
X344763Y354543D01*
X344777Y354529D01*
X345068Y354294D01*
X345359Y354072D01*
X345637Y353878D01*
X345914Y353725D01*
X346150Y353587D01*
X346247Y353531D01*
X346330Y353489D01*
X346399Y353448D01*
X346455Y353434D01*
X346483Y353406D01*
X346497D01*
Y352269D01*
X346288Y352352D01*
X346080Y352449D01*
X345872Y352546D01*
X345678Y352643D01*
X345512Y352727D01*
X345373Y352796D01*
X345290Y352851D01*
X345276Y352865D01*
X345262D01*
X345013Y353018D01*
X344791Y353170D01*
X344596Y353309D01*
X344444Y353434D01*
X344305Y353531D01*
X344222Y353614D01*
X344153Y353670D01*
X344139Y353684D01*
Y346181D01*
X342960D01*
Y355819D01*
X343723D01*
X343862Y355583D01*
D02*
G37*
G36*
X364040Y346181D02*
X362764D01*
Y350438D01*
X361128D01*
X360975Y350424D01*
X360864D01*
X360767Y350411D01*
X360698Y350397D01*
X360642D01*
X360615Y350383D01*
X360601D01*
X360379Y350313D01*
X360282Y350272D01*
X360198Y350230D01*
X360115Y350189D01*
X360060Y350161D01*
X360032Y350147D01*
X360018Y350133D01*
X359907Y350050D01*
X359796Y349953D01*
X359588Y349745D01*
X359491Y349648D01*
X359422Y349565D01*
X359380Y349509D01*
X359366Y349495D01*
X359228Y349301D01*
X359075Y349093D01*
X358923Y348871D01*
X358770Y348663D01*
X358645Y348469D01*
X358548Y348316D01*
X358507Y348261D01*
X358479Y348219D01*
X358451Y348192D01*
Y348178D01*
X357189Y346181D01*
X355608D01*
X357258Y348788D01*
X357453Y349065D01*
X357633Y349315D01*
X357813Y349523D01*
X357966Y349717D01*
X358104Y349856D01*
X358215Y349967D01*
X358285Y350036D01*
X358312Y350064D01*
X358423Y350147D01*
X358548Y350244D01*
X358798Y350397D01*
X358909Y350452D01*
X358992Y350508D01*
X359047Y350535D01*
X359075Y350549D01*
X358825Y350591D01*
X358590Y350633D01*
X358382Y350702D01*
X358174Y350757D01*
X357993Y350827D01*
X357827Y350910D01*
X357674Y350979D01*
X357536Y351049D01*
X357425Y351132D01*
X357314Y351201D01*
X357231Y351257D01*
X357161Y351312D01*
X357106Y351354D01*
X357064Y351395D01*
X357050Y351409D01*
X357036Y351423D01*
X356926Y351562D01*
X356815Y351700D01*
X356648Y351992D01*
X356537Y352283D01*
X356454Y352560D01*
X356399Y352796D01*
X356385Y352893D01*
Y352990D01*
X356371Y353060D01*
Y353115D01*
Y353143D01*
Y353157D01*
X356385Y353448D01*
X356426Y353711D01*
X356496Y353961D01*
X356565Y354169D01*
X356648Y354349D01*
X356704Y354488D01*
X356759Y354571D01*
X356773Y354585D01*
Y354599D01*
X356939Y354821D01*
X357106Y355015D01*
X357286Y355181D01*
X357453Y355306D01*
X357605Y355403D01*
X357730Y355459D01*
X357813Y355500D01*
X357827Y355514D01*
X357841D01*
X357966Y355556D01*
X358118Y355597D01*
X358423Y355667D01*
X358756Y355708D01*
X359061Y355750D01*
X359352Y355764D01*
X359477D01*
X359588Y355778D01*
X364040D01*
Y346181D01*
D02*
G37*
G36*
X352348Y344139D02*
X352584Y344125D01*
X352806Y344083D01*
X353014Y344042D01*
X353208Y343986D01*
X353388Y343931D01*
X353555Y343861D01*
X353707Y343792D01*
X353846Y343723D01*
X353957Y343653D01*
X354054Y343598D01*
X354137Y343542D01*
X354207Y343501D01*
X354248Y343459D01*
X354276Y343445D01*
X354290Y343431D01*
X354428Y343293D01*
X354553Y343140D01*
X354678Y342974D01*
X354775Y342807D01*
X354942Y342474D01*
X355052Y342142D01*
X355094Y341989D01*
X355136Y341837D01*
X355163Y341712D01*
X355191Y341601D01*
X355205Y341504D01*
Y341434D01*
X355219Y341393D01*
Y341379D01*
X354012Y341254D01*
X353985Y341573D01*
X353929Y341850D01*
X353846Y342100D01*
X353749Y342294D01*
X353666Y342461D01*
X353582Y342571D01*
X353527Y342641D01*
X353499Y342669D01*
X353291Y342835D01*
X353069Y342960D01*
X352834Y343057D01*
X352626Y343112D01*
X352431Y343154D01*
X352265Y343168D01*
X352210Y343182D01*
X352126D01*
X351835Y343168D01*
X351572Y343112D01*
X351350Y343029D01*
X351156Y342946D01*
X351003Y342849D01*
X350906Y342780D01*
X350836Y342724D01*
X350809Y342696D01*
X350642Y342502D01*
X350518Y342308D01*
X350420Y342114D01*
X350365Y341920D01*
X350323Y341767D01*
X350309Y341628D01*
X350296Y341545D01*
Y341531D01*
Y341517D01*
X350323Y341268D01*
X350379Y341004D01*
X350476Y340769D01*
X350573Y340547D01*
X350684Y340366D01*
X350781Y340214D01*
X350809Y340158D01*
X350836Y340117D01*
X350864Y340103D01*
Y340089D01*
X350975Y339936D01*
X351114Y339784D01*
X351267Y339618D01*
X351433Y339451D01*
X351780Y339118D01*
X352126Y338785D01*
X352307Y338633D01*
X352459Y338494D01*
X352612Y338369D01*
X352737Y338258D01*
X352834Y338175D01*
X352917Y338106D01*
X352972Y338064D01*
X352986Y338050D01*
X353333Y337759D01*
X353652Y337482D01*
X353915Y337232D01*
X354123Y337024D01*
X354304Y336844D01*
X354428Y336719D01*
X354498Y336636D01*
X354525Y336622D01*
Y336608D01*
X354720Y336372D01*
X354872Y336150D01*
X355011Y335928D01*
X355122Y335734D01*
X355205Y335568D01*
X355261Y335443D01*
X355288Y335360D01*
X355302Y335346D01*
Y335332D01*
X355358Y335180D01*
X355385Y335041D01*
X355413Y334902D01*
X355427Y334777D01*
X355441Y334666D01*
Y334583D01*
Y334528D01*
Y334514D01*
X349075D01*
Y335651D01*
X353804D01*
X353638Y335887D01*
X353555Y335984D01*
X353485Y336081D01*
X353416Y336164D01*
X353361Y336220D01*
X353319Y336261D01*
X353305Y336275D01*
X353236Y336345D01*
X353153Y336414D01*
X352958Y336594D01*
X352737Y336802D01*
X352501Y337010D01*
X352279Y337191D01*
X352182Y337274D01*
X352099Y337357D01*
X352029Y337412D01*
X351974Y337454D01*
X351946Y337482D01*
X351932Y337496D01*
X351710Y337690D01*
X351488Y337870D01*
X351294Y338050D01*
X351114Y338203D01*
X350947Y338355D01*
X350809Y338494D01*
X350670Y338619D01*
X350559Y338730D01*
X350448Y338841D01*
X350365Y338924D01*
X350296Y338993D01*
X350226Y339063D01*
X350157Y339146D01*
X350129Y339174D01*
X349935Y339409D01*
X349769Y339618D01*
X349630Y339826D01*
X349519Y339992D01*
X349436Y340145D01*
X349380Y340256D01*
X349353Y340325D01*
X349339Y340353D01*
X349255Y340561D01*
X349200Y340769D01*
X349145Y340963D01*
X349117Y341129D01*
X349103Y341282D01*
X349089Y341393D01*
Y341462D01*
Y341490D01*
X349103Y341698D01*
X349131Y341892D01*
X349159Y342086D01*
X349214Y342253D01*
X349353Y342585D01*
X349491Y342849D01*
X349575Y342974D01*
X349644Y343071D01*
X349713Y343168D01*
X349782Y343237D01*
X349838Y343293D01*
X349866Y343348D01*
X349893Y343362D01*
X349907Y343376D01*
X350060Y343515D01*
X350226Y343639D01*
X350407Y343736D01*
X350587Y343820D01*
X350947Y343958D01*
X351308Y344055D01*
X351461Y344083D01*
X351613Y344111D01*
X351752Y344125D01*
X351863Y344139D01*
X351960Y344152D01*
X352099D01*
X352348Y344139D01*
D02*
G37*
G36*
X364455Y334514D02*
X363179D01*
Y338772D01*
X361543D01*
X361390Y338758D01*
X361279D01*
X361182Y338744D01*
X361113Y338730D01*
X361058D01*
X361030Y338716D01*
X361016D01*
X360794Y338647D01*
X360697Y338605D01*
X360614Y338563D01*
X360531Y338522D01*
X360475Y338494D01*
X360447Y338480D01*
X360434Y338466D01*
X360322Y338383D01*
X360212Y338286D01*
X360004Y338078D01*
X359907Y337981D01*
X359837Y337898D01*
X359795Y337842D01*
X359782Y337828D01*
X359643Y337634D01*
X359490Y337426D01*
X359338Y337204D01*
X359185Y336996D01*
X359061Y336802D01*
X358963Y336650D01*
X358922Y336594D01*
X358894Y336553D01*
X358866Y336525D01*
Y336511D01*
X357604Y334514D01*
X356023D01*
X357674Y337121D01*
X357868Y337399D01*
X358048Y337648D01*
X358228Y337856D01*
X358381Y338050D01*
X358520Y338189D01*
X358631Y338300D01*
X358700Y338369D01*
X358728Y338397D01*
X358839Y338480D01*
X358963Y338577D01*
X359213Y338730D01*
X359324Y338785D01*
X359407Y338841D01*
X359463Y338869D01*
X359490Y338882D01*
X359241Y338924D01*
X359005Y338966D01*
X358797Y339035D01*
X358589Y339090D01*
X358409Y339160D01*
X358242Y339243D01*
X358090Y339312D01*
X357951Y339382D01*
X357840Y339465D01*
X357729Y339534D01*
X357646Y339590D01*
X357577Y339645D01*
X357521Y339687D01*
X357480Y339729D01*
X357466Y339742D01*
X357452Y339756D01*
X357341Y339895D01*
X357230Y340034D01*
X357063Y340325D01*
X356953Y340616D01*
X356869Y340893D01*
X356814Y341129D01*
X356800Y341226D01*
Y341323D01*
X356786Y341393D01*
Y341448D01*
Y341476D01*
Y341490D01*
X356800Y341781D01*
X356842Y342044D01*
X356911Y342294D01*
X356980Y342502D01*
X357063Y342682D01*
X357119Y342821D01*
X357174Y342904D01*
X357188Y342918D01*
Y342932D01*
X357355Y343154D01*
X357521Y343348D01*
X357701Y343515D01*
X357868Y343639D01*
X358020Y343736D01*
X358145Y343792D01*
X358228Y343834D01*
X358242Y343847D01*
X358256D01*
X358381Y343889D01*
X358534Y343931D01*
X358839Y344000D01*
X359171Y344042D01*
X359477Y344083D01*
X359768Y344097D01*
X359893D01*
X360004Y344111D01*
X364455D01*
Y334514D01*
D02*
G37*
G36*
X345053Y344125D02*
X345400Y344069D01*
X345691Y343972D01*
X345941Y343875D01*
X346149Y343764D01*
X346232Y343723D01*
X346302Y343667D01*
X346357Y343639D01*
X346399Y343612D01*
X346413Y343584D01*
X346426D01*
X346676Y343362D01*
X346884Y343098D01*
X347064Y342835D01*
X347203Y342585D01*
X347314Y342350D01*
X347369Y342253D01*
X347397Y342155D01*
X347425Y342086D01*
X347453Y342031D01*
X347467Y342003D01*
Y341989D01*
X347522Y341781D01*
X347578Y341573D01*
X347661Y341115D01*
X347730Y340658D01*
X347772Y340228D01*
X347785Y340020D01*
X347799Y339839D01*
Y339673D01*
X347813Y339520D01*
Y339409D01*
Y339312D01*
Y339257D01*
Y339243D01*
X347799Y338758D01*
X347772Y338300D01*
X347730Y337884D01*
X347661Y337496D01*
X347591Y337135D01*
X347508Y336816D01*
X347425Y336525D01*
X347342Y336275D01*
X347258Y336053D01*
X347161Y335859D01*
X347092Y335693D01*
X347023Y335568D01*
X346953Y335457D01*
X346912Y335388D01*
X346884Y335346D01*
X346870Y335332D01*
X346718Y335166D01*
X346551Y335013D01*
X346371Y334874D01*
X346191Y334764D01*
X346010Y334666D01*
X345830Y334583D01*
X345650Y334528D01*
X345483Y334472D01*
X345317Y334431D01*
X345164Y334403D01*
X345026Y334375D01*
X344915Y334361D01*
X344818Y334347D01*
X344679D01*
X344305Y334375D01*
X343958Y334431D01*
X343667Y334528D01*
X343417Y334625D01*
X343209Y334722D01*
X343140Y334777D01*
X343070Y334819D01*
X343015Y334847D01*
X342973Y334874D01*
X342959Y334902D01*
X342945D01*
X342696Y335138D01*
X342488Y335388D01*
X342308Y335665D01*
X342169Y335915D01*
X342058Y336150D01*
X342002Y336247D01*
X341975Y336345D01*
X341947Y336414D01*
X341919Y336469D01*
X341905Y336497D01*
Y336511D01*
X341836Y336719D01*
X341781Y336927D01*
X341697Y337371D01*
X341628Y337828D01*
X341586Y338272D01*
X341572Y338466D01*
X341559Y338647D01*
Y338813D01*
X341545Y338966D01*
Y339077D01*
Y339174D01*
Y339229D01*
Y339243D01*
Y339507D01*
X341559Y339756D01*
Y339978D01*
X341572Y340200D01*
X341600Y340394D01*
X341614Y340588D01*
X341628Y340755D01*
X341656Y340907D01*
X341670Y341046D01*
X341697Y341171D01*
X341711Y341268D01*
X341725Y341351D01*
X341739Y341420D01*
X341753Y341462D01*
X341767Y341490D01*
Y341504D01*
X341850Y341809D01*
X341947Y342086D01*
X342058Y342322D01*
X342141Y342530D01*
X342238Y342710D01*
X342294Y342835D01*
X342349Y342904D01*
X342363Y342932D01*
X342515Y343140D01*
X342668Y343320D01*
X342835Y343473D01*
X342987Y343612D01*
X343126Y343709D01*
X343237Y343778D01*
X343306Y343820D01*
X343320Y343834D01*
X343334D01*
X343556Y343945D01*
X343791Y344014D01*
X344013Y344069D01*
X344221Y344111D01*
X344402Y344139D01*
X344554Y344152D01*
X344679D01*
X345053Y344125D01*
D02*
G37*
G36*
X56759Y358667D02*
X56911Y358445D01*
X57092Y358223D01*
X57258Y358029D01*
X57425Y357862D01*
X57549Y357724D01*
X57605Y357682D01*
X57646Y357640D01*
X57660Y357627D01*
X57674Y357613D01*
X57965Y357377D01*
X58257Y357155D01*
X58534Y356961D01*
X58811Y356808D01*
X59047Y356670D01*
X59144Y356614D01*
X59227Y356573D01*
X59297Y356531D01*
X59352Y356517D01*
X59380Y356489D01*
X59394D01*
Y355352D01*
X59186Y355435D01*
X58978Y355532D01*
X58770Y355630D01*
X58576Y355727D01*
X58409Y355810D01*
X58270Y355879D01*
X58187Y355935D01*
X58173Y355948D01*
X58159D01*
X57910Y356101D01*
X57688Y356254D01*
X57494Y356392D01*
X57341Y356517D01*
X57203Y356614D01*
X57119Y356697D01*
X57050Y356753D01*
X57036Y356767D01*
Y349264D01*
X55857D01*
Y358903D01*
X56620D01*
X56759Y358667D01*
D02*
G37*
G36*
X50060Y358889D02*
X50282Y358861D01*
X50504Y358819D01*
X50698Y358764D01*
X51073Y358611D01*
X51239Y358542D01*
X51378Y358459D01*
X51516Y358362D01*
X51627Y358292D01*
X51738Y358209D01*
X51822Y358140D01*
X51891Y358084D01*
X51933Y358043D01*
X51960Y358015D01*
X51974Y358001D01*
X52127Y357835D01*
X52252Y357640D01*
X52376Y357460D01*
X52474Y357266D01*
X52557Y357058D01*
X52626Y356864D01*
X52723Y356503D01*
X52765Y356323D01*
X52792Y356170D01*
X52806Y356018D01*
X52820Y355893D01*
X52834Y355796D01*
Y355727D01*
Y355671D01*
Y355657D01*
X52820Y355394D01*
X52792Y355158D01*
X52765Y354922D01*
X52709Y354700D01*
X52640Y354506D01*
X52571Y354312D01*
X52501Y354146D01*
X52418Y353993D01*
X52349Y353854D01*
X52279Y353730D01*
X52210Y353633D01*
X52141Y353535D01*
X52085Y353466D01*
X52057Y353424D01*
X52030Y353397D01*
X52016Y353383D01*
X51863Y353230D01*
X51697Y353106D01*
X51530Y352981D01*
X51350Y352884D01*
X51184Y352800D01*
X51017Y352731D01*
X50698Y352634D01*
X50560Y352592D01*
X50421Y352565D01*
X50310Y352551D01*
X50199Y352537D01*
X50116Y352523D01*
X50005D01*
X49741Y352537D01*
X49492Y352579D01*
X49270Y352634D01*
X49062Y352703D01*
X48909Y352759D01*
X48784Y352814D01*
X48701Y352856D01*
X48674Y352870D01*
X48452Y353008D01*
X48257Y353161D01*
X48091Y353313D01*
X47952Y353452D01*
X47855Y353591D01*
X47772Y353688D01*
X47717Y353757D01*
X47703Y353785D01*
Y353674D01*
Y353605D01*
Y353563D01*
Y353549D01*
X47717Y353272D01*
X47730Y353008D01*
X47758Y352773D01*
X47786Y352551D01*
X47828Y352370D01*
X47855Y352232D01*
X47869Y352176D01*
Y352135D01*
X47883Y352121D01*
Y352107D01*
X47952Y351857D01*
X48022Y351635D01*
X48091Y351441D01*
X48160Y351275D01*
X48216Y351150D01*
X48271Y351053D01*
X48299Y350984D01*
X48313Y350970D01*
X48424Y350817D01*
X48535Y350692D01*
X48646Y350581D01*
X48757Y350484D01*
X48840Y350401D01*
X48923Y350346D01*
X48979Y350318D01*
X48993Y350304D01*
X49145Y350221D01*
X49311Y350165D01*
X49464Y350124D01*
X49617Y350096D01*
X49741Y350082D01*
X49839Y350068D01*
X49935D01*
X50157Y350082D01*
X50366Y350124D01*
X50546Y350179D01*
X50698Y350249D01*
X50809Y350304D01*
X50906Y350359D01*
X50962Y350401D01*
X50976Y350415D01*
X51114Y350568D01*
X51225Y350748D01*
X51322Y350942D01*
X51392Y351136D01*
X51447Y351303D01*
X51489Y351455D01*
X51503Y351511D01*
Y351538D01*
X51516Y351566D01*
Y351580D01*
X52654Y351483D01*
X52571Y351081D01*
X52460Y350734D01*
X52321Y350429D01*
X52182Y350179D01*
X52043Y349985D01*
X51974Y349902D01*
X51919Y349832D01*
X51877Y349791D01*
X51835Y349749D01*
X51822Y349735D01*
X51808Y349722D01*
X51669Y349611D01*
X51516Y349514D01*
X51211Y349361D01*
X50906Y349250D01*
X50615Y349181D01*
X50352Y349125D01*
X50241Y349111D01*
X50144D01*
X50074Y349098D01*
X49963D01*
X49575Y349125D01*
X49228Y349181D01*
X48909Y349278D01*
X48646Y349389D01*
X48535Y349430D01*
X48424Y349486D01*
X48341Y349541D01*
X48257Y349583D01*
X48202Y349611D01*
X48160Y349638D01*
X48133Y349666D01*
X48119D01*
X47841Y349902D01*
X47592Y350165D01*
X47398Y350443D01*
X47231Y350706D01*
X47092Y350942D01*
X47037Y351053D01*
X46995Y351136D01*
X46968Y351219D01*
X46940Y351275D01*
X46926Y351303D01*
Y351316D01*
X46857Y351525D01*
X46787Y351760D01*
X46690Y352232D01*
X46621Y352731D01*
X46579Y353203D01*
X46552Y353411D01*
X46538Y353619D01*
Y353799D01*
X46524Y353951D01*
Y354076D01*
Y354173D01*
Y354243D01*
Y354257D01*
Y354576D01*
X46538Y354881D01*
X46565Y355158D01*
X46593Y355421D01*
X46621Y355657D01*
X46649Y355879D01*
X46690Y356087D01*
X46732Y356268D01*
X46774Y356420D01*
X46801Y356559D01*
X46843Y356684D01*
X46871Y356781D01*
X46898Y356850D01*
X46926Y356905D01*
X46940Y356933D01*
Y356947D01*
X47106Y357280D01*
X47287Y357571D01*
X47495Y357821D01*
X47675Y358029D01*
X47855Y358181D01*
X47994Y358292D01*
X48049Y358334D01*
X48091Y358362D01*
X48105Y358389D01*
X48119D01*
X48410Y358556D01*
X48701Y358681D01*
X48993Y358778D01*
X49256Y358833D01*
X49492Y358875D01*
X49589Y358889D01*
X49658D01*
X49728Y358903D01*
X49825D01*
X50060Y358889D01*
D02*
G37*
G36*
X69476Y349264D02*
X68200D01*
Y353521D01*
X66564D01*
X66411Y353508D01*
X66300D01*
X66203Y353494D01*
X66134Y353480D01*
X66078D01*
X66051Y353466D01*
X66037D01*
X65815Y353397D01*
X65718Y353355D01*
X65635Y353313D01*
X65551Y353272D01*
X65496Y353244D01*
X65468Y353230D01*
X65454Y353216D01*
X65343Y353133D01*
X65232Y353036D01*
X65024Y352828D01*
X64927Y352731D01*
X64858Y352648D01*
X64816Y352592D01*
X64802Y352579D01*
X64664Y352384D01*
X64511Y352176D01*
X64359Y351954D01*
X64206Y351746D01*
X64081Y351552D01*
X63984Y351400D01*
X63943Y351344D01*
X63915Y351303D01*
X63887Y351275D01*
Y351261D01*
X62625Y349264D01*
X61044D01*
X62695Y351871D01*
X62889Y352149D01*
X63069Y352398D01*
X63249Y352606D01*
X63402Y352800D01*
X63540Y352939D01*
X63651Y353050D01*
X63721Y353119D01*
X63748Y353147D01*
X63859Y353230D01*
X63984Y353327D01*
X64234Y353480D01*
X64345Y353535D01*
X64428Y353591D01*
X64483Y353619D01*
X64511Y353633D01*
X64262Y353674D01*
X64026Y353716D01*
X63818Y353785D01*
X63610Y353840D01*
X63429Y353910D01*
X63263Y353993D01*
X63110Y354062D01*
X62972Y354132D01*
X62861Y354215D01*
X62750Y354284D01*
X62667Y354340D01*
X62597Y354395D01*
X62542Y354437D01*
X62500Y354478D01*
X62486Y354492D01*
X62473Y354506D01*
X62362Y354645D01*
X62251Y354784D01*
X62084Y355075D01*
X61973Y355366D01*
X61890Y355643D01*
X61835Y355879D01*
X61821Y355976D01*
Y356073D01*
X61807Y356143D01*
Y356198D01*
Y356226D01*
Y356240D01*
X61821Y356531D01*
X61862Y356795D01*
X61932Y357044D01*
X62001Y357252D01*
X62084Y357432D01*
X62140Y357571D01*
X62195Y357654D01*
X62209Y357668D01*
Y357682D01*
X62375Y357904D01*
X62542Y358098D01*
X62722Y358265D01*
X62889Y358389D01*
X63041Y358486D01*
X63166Y358542D01*
X63249Y358583D01*
X63263Y358597D01*
X63277D01*
X63402Y358639D01*
X63554Y358681D01*
X63859Y358750D01*
X64192Y358792D01*
X64497Y358833D01*
X64789Y358847D01*
X64913D01*
X65024Y358861D01*
X69476D01*
Y349264D01*
D02*
G37*
G36*
X56259Y346417D02*
X56411Y346195D01*
X56592Y345973D01*
X56758Y345779D01*
X56925Y345612D01*
X57049Y345474D01*
X57105Y345432D01*
X57146Y345390D01*
X57160Y345377D01*
X57174Y345363D01*
X57465Y345127D01*
X57757Y344905D01*
X58034Y344711D01*
X58311Y344558D01*
X58547Y344420D01*
X58644Y344364D01*
X58727Y344323D01*
X58797Y344281D01*
X58852Y344267D01*
X58880Y344239D01*
X58894D01*
Y343102D01*
X58686Y343185D01*
X58478Y343282D01*
X58270Y343380D01*
X58076Y343477D01*
X57909Y343560D01*
X57770Y343629D01*
X57687Y343685D01*
X57673Y343699D01*
X57660D01*
X57410Y343851D01*
X57188Y344004D01*
X56994Y344142D01*
X56841Y344267D01*
X56703Y344364D01*
X56619Y344447D01*
X56550Y344503D01*
X56536Y344517D01*
Y337014D01*
X55357D01*
Y346652D01*
X56120D01*
X56259Y346417D01*
D02*
G37*
G36*
X68976Y337014D02*
X67700D01*
Y341272D01*
X66064D01*
X65911Y341258D01*
X65800D01*
X65703Y341244D01*
X65634Y341230D01*
X65578D01*
X65551Y341216D01*
X65537D01*
X65315Y341147D01*
X65218Y341105D01*
X65135Y341063D01*
X65051Y341022D01*
X64996Y340994D01*
X64968Y340980D01*
X64954Y340966D01*
X64843Y340883D01*
X64732Y340786D01*
X64524Y340578D01*
X64427Y340481D01*
X64358Y340398D01*
X64316Y340342D01*
X64303Y340328D01*
X64164Y340134D01*
X64011Y339926D01*
X63859Y339704D01*
X63706Y339496D01*
X63581Y339302D01*
X63484Y339150D01*
X63443Y339094D01*
X63415Y339053D01*
X63387Y339025D01*
Y339011D01*
X62125Y337014D01*
X60544D01*
X62194Y339621D01*
X62389Y339899D01*
X62569Y340148D01*
X62749Y340356D01*
X62902Y340550D01*
X63040Y340689D01*
X63151Y340800D01*
X63221Y340869D01*
X63249Y340897D01*
X63359Y340980D01*
X63484Y341077D01*
X63734Y341230D01*
X63845Y341285D01*
X63928Y341341D01*
X63983Y341369D01*
X64011Y341382D01*
X63762Y341424D01*
X63526Y341466D01*
X63318Y341535D01*
X63110Y341590D01*
X62930Y341660D01*
X62763Y341743D01*
X62611Y341812D01*
X62472Y341882D01*
X62361Y341965D01*
X62250Y342034D01*
X62167Y342090D01*
X62097Y342145D01*
X62042Y342187D01*
X62000Y342228D01*
X61986Y342242D01*
X61973Y342256D01*
X61862Y342395D01*
X61751Y342534D01*
X61584Y342825D01*
X61473Y343116D01*
X61390Y343393D01*
X61335Y343629D01*
X61321Y343726D01*
Y343823D01*
X61307Y343893D01*
Y343948D01*
Y343976D01*
Y343990D01*
X61321Y344281D01*
X61362Y344544D01*
X61432Y344794D01*
X61501Y345002D01*
X61584Y345182D01*
X61640Y345321D01*
X61695Y345404D01*
X61709Y345418D01*
Y345432D01*
X61876Y345654D01*
X62042Y345848D01*
X62222Y346015D01*
X62389Y346139D01*
X62541Y346236D01*
X62666Y346292D01*
X62749Y346334D01*
X62763Y346347D01*
X62777D01*
X62902Y346389D01*
X63054Y346431D01*
X63359Y346500D01*
X63692Y346541D01*
X63997Y346583D01*
X64289Y346597D01*
X64413D01*
X64524Y346611D01*
X68976D01*
Y337014D01*
D02*
G37*
G36*
X49436Y346639D02*
X49657Y346625D01*
X50046Y346541D01*
X50226Y346486D01*
X50392Y346431D01*
X50545Y346361D01*
X50684Y346292D01*
X50795Y346222D01*
X50906Y346153D01*
X51003Y346098D01*
X51072Y346042D01*
X51128Y346001D01*
X51169Y345959D01*
X51197Y345945D01*
X51211Y345931D01*
X51336Y345793D01*
X51460Y345654D01*
X51557Y345501D01*
X51641Y345349D01*
X51779Y345058D01*
X51863Y344780D01*
X51918Y344544D01*
X51932Y344434D01*
X51946Y344350D01*
X51960Y344267D01*
Y344212D01*
Y344184D01*
Y344170D01*
X51946Y343920D01*
X51904Y343685D01*
X51849Y343477D01*
X51779Y343296D01*
X51724Y343158D01*
X51668Y343047D01*
X51627Y342991D01*
X51613Y342963D01*
X51460Y342797D01*
X51294Y342645D01*
X51114Y342506D01*
X50933Y342395D01*
X50767Y342312D01*
X50642Y342256D01*
X50587Y342228D01*
X50545Y342215D01*
X50531Y342201D01*
X50517D01*
X50836Y342104D01*
X51100Y341979D01*
X51336Y341826D01*
X51530Y341688D01*
X51682Y341549D01*
X51793Y341438D01*
X51849Y341369D01*
X51876Y341355D01*
Y341341D01*
X52029Y341091D01*
X52154Y340828D01*
X52237Y340578D01*
X52292Y340328D01*
X52320Y340107D01*
X52334Y340009D01*
Y339926D01*
X52348Y339871D01*
Y339815D01*
Y339788D01*
Y339774D01*
X52334Y339552D01*
X52306Y339330D01*
X52265Y339122D01*
X52209Y338914D01*
X52070Y338567D01*
X52001Y338401D01*
X51918Y338262D01*
X51835Y338123D01*
X51765Y338013D01*
X51682Y337915D01*
X51627Y337832D01*
X51571Y337763D01*
X51530Y337721D01*
X51502Y337693D01*
X51488Y337680D01*
X51322Y337527D01*
X51141Y337402D01*
X50947Y337291D01*
X50753Y337194D01*
X50573Y337125D01*
X50379Y337056D01*
X50004Y336959D01*
X49838Y336917D01*
X49685Y336889D01*
X49546Y336875D01*
X49422Y336861D01*
X49325Y336847D01*
X49186D01*
X48922Y336861D01*
X48687Y336889D01*
X48451Y336931D01*
X48229Y336972D01*
X48035Y337042D01*
X47841Y337111D01*
X47660Y337180D01*
X47508Y337264D01*
X47369Y337347D01*
X47244Y337416D01*
X47147Y337486D01*
X47050Y337555D01*
X46981Y337596D01*
X46939Y337638D01*
X46912Y337666D01*
X46898Y337680D01*
X46745Y337846D01*
X46606Y338013D01*
X46495Y338179D01*
X46398Y338359D01*
X46301Y338526D01*
X46232Y338706D01*
X46135Y339025D01*
X46093Y339177D01*
X46066Y339316D01*
X46052Y339441D01*
X46038Y339538D01*
X46024Y339621D01*
Y339691D01*
Y339732D01*
Y339746D01*
X46038Y340065D01*
X46093Y340356D01*
X46177Y340620D01*
X46260Y340842D01*
X46343Y341022D01*
X46426Y341161D01*
X46482Y341244D01*
X46495Y341258D01*
Y341272D01*
X46690Y341493D01*
X46898Y341688D01*
X47119Y341840D01*
X47327Y341979D01*
X47522Y342076D01*
X47688Y342145D01*
X47744Y342173D01*
X47785Y342187D01*
X47813Y342201D01*
X47827D01*
X47577Y342312D01*
X47369Y342436D01*
X47189Y342561D01*
X47036Y342686D01*
X46925Y342797D01*
X46842Y342880D01*
X46787Y342936D01*
X46773Y342963D01*
X46648Y343158D01*
X46565Y343352D01*
X46495Y343546D01*
X46454Y343740D01*
X46426Y343893D01*
X46412Y344017D01*
Y344101D01*
Y344115D01*
Y344128D01*
X46426Y344323D01*
X46440Y344503D01*
X46537Y344850D01*
X46662Y345155D01*
X46800Y345418D01*
X46939Y345626D01*
X47009Y345709D01*
X47064Y345793D01*
X47119Y345848D01*
X47161Y345890D01*
X47175Y345904D01*
X47189Y345917D01*
X47341Y346042D01*
X47494Y346167D01*
X47660Y346264D01*
X47827Y346347D01*
X48160Y346472D01*
X48492Y346555D01*
X48631Y346597D01*
X48770Y346611D01*
X48895Y346625D01*
X49006Y346639D01*
X49089Y346652D01*
X49214D01*
X49436Y346639D01*
D02*
G37*
G36*
X18252Y339084D02*
X18404Y338862D01*
X18585Y338640D01*
X18751Y338446D01*
X18917Y338279D01*
X19042Y338140D01*
X19098Y338099D01*
X19139Y338057D01*
X19153Y338043D01*
X19167Y338030D01*
X19458Y337794D01*
X19750Y337572D01*
X20027Y337378D01*
X20304Y337225D01*
X20540Y337086D01*
X20637Y337031D01*
X20720Y336989D01*
X20790Y336948D01*
X20845Y336934D01*
X20873Y336906D01*
X20887D01*
Y335769D01*
X20679Y335852D01*
X20471Y335949D01*
X20263Y336046D01*
X20069Y336143D01*
X19902Y336227D01*
X19763Y336296D01*
X19680Y336351D01*
X19666Y336365D01*
X19653D01*
X19403Y336518D01*
X19181Y336670D01*
X18987Y336809D01*
X18834Y336934D01*
X18696Y337031D01*
X18612Y337114D01*
X18543Y337170D01*
X18529Y337183D01*
Y329681D01*
X17350D01*
Y339319D01*
X18113D01*
X18252Y339084D01*
D02*
G37*
G36*
X30969Y329681D02*
X29693D01*
Y333938D01*
X28057D01*
X27904Y333924D01*
X27793D01*
X27696Y333911D01*
X27627Y333897D01*
X27571D01*
X27544Y333883D01*
X27530D01*
X27308Y333814D01*
X27211Y333772D01*
X27128Y333730D01*
X27044Y333689D01*
X26989Y333661D01*
X26961Y333647D01*
X26947Y333633D01*
X26836Y333550D01*
X26725Y333453D01*
X26517Y333245D01*
X26420Y333148D01*
X26351Y333065D01*
X26309Y333009D01*
X26295Y332995D01*
X26157Y332801D01*
X26004Y332593D01*
X25852Y332371D01*
X25699Y332163D01*
X25574Y331969D01*
X25477Y331816D01*
X25436Y331761D01*
X25408Y331719D01*
X25380Y331692D01*
Y331678D01*
X24118Y329681D01*
X22537D01*
X24188Y332288D01*
X24382Y332565D01*
X24562Y332815D01*
X24742Y333023D01*
X24895Y333217D01*
X25034Y333356D01*
X25145Y333467D01*
X25214Y333536D01*
X25241Y333564D01*
X25352Y333647D01*
X25477Y333744D01*
X25727Y333897D01*
X25838Y333952D01*
X25921Y334008D01*
X25977Y334035D01*
X26004Y334049D01*
X25755Y334091D01*
X25519Y334132D01*
X25311Y334202D01*
X25103Y334257D01*
X24923Y334327D01*
X24756Y334410D01*
X24604Y334479D01*
X24465Y334548D01*
X24354Y334632D01*
X24243Y334701D01*
X24160Y334757D01*
X24090Y334812D01*
X24035Y334854D01*
X23993Y334895D01*
X23979Y334909D01*
X23966Y334923D01*
X23855Y335062D01*
X23744Y335200D01*
X23577Y335492D01*
X23466Y335783D01*
X23383Y336060D01*
X23328Y336296D01*
X23314Y336393D01*
Y336490D01*
X23300Y336559D01*
Y336615D01*
Y336643D01*
Y336656D01*
X23314Y336948D01*
X23355Y337211D01*
X23425Y337461D01*
X23494Y337669D01*
X23577Y337849D01*
X23633Y337988D01*
X23688Y338071D01*
X23702Y338085D01*
Y338099D01*
X23869Y338321D01*
X24035Y338515D01*
X24215Y338681D01*
X24382Y338806D01*
X24534Y338903D01*
X24659Y338959D01*
X24742Y339000D01*
X24756Y339014D01*
X24770D01*
X24895Y339056D01*
X25047Y339097D01*
X25352Y339167D01*
X25685Y339208D01*
X25990Y339250D01*
X26282Y339264D01*
X26407D01*
X26517Y339278D01*
X30969D01*
Y329681D01*
D02*
G37*
G36*
X14244Y338016D02*
X9542D01*
X9875Y337613D01*
X10194Y337183D01*
X10472Y336768D01*
X10735Y336365D01*
X10846Y336185D01*
X10943Y336019D01*
X11040Y335866D01*
X11110Y335741D01*
X11165Y335630D01*
X11207Y335561D01*
X11234Y335505D01*
X11248Y335492D01*
X11526Y334937D01*
X11775Y334382D01*
X11983Y333855D01*
X12067Y333619D01*
X12150Y333384D01*
X12233Y333176D01*
X12288Y332981D01*
X12344Y332815D01*
X12385Y332676D01*
X12427Y332551D01*
X12455Y332468D01*
X12469Y332413D01*
Y332399D01*
X12607Y331830D01*
X12663Y331553D01*
X12704Y331303D01*
X12746Y331068D01*
X12788Y330832D01*
X12815Y330638D01*
X12843Y330443D01*
X12857Y330277D01*
X12871Y330125D01*
X12885Y329986D01*
Y329875D01*
X12899Y329792D01*
Y329736D01*
Y329695D01*
Y329681D01*
X11692D01*
X11651Y330208D01*
X11581Y330693D01*
X11512Y331137D01*
X11470Y331345D01*
X11429Y331539D01*
X11401Y331706D01*
X11359Y331858D01*
X11331Y331997D01*
X11304Y332108D01*
X11276Y332191D01*
X11262Y332260D01*
X11248Y332302D01*
Y332316D01*
X11040Y332954D01*
X10818Y333550D01*
X10707Y333841D01*
X10596Y334119D01*
X10472Y334368D01*
X10361Y334618D01*
X10264Y334840D01*
X10167Y335034D01*
X10083Y335200D01*
X10014Y335353D01*
X9945Y335478D01*
X9903Y335561D01*
X9875Y335616D01*
X9862Y335630D01*
X9695Y335922D01*
X9529Y336213D01*
X9362Y336476D01*
X9196Y336726D01*
X9043Y336948D01*
X8891Y337170D01*
X8738Y337364D01*
X8613Y337530D01*
X8489Y337697D01*
X8378Y337835D01*
X8267Y337946D01*
X8183Y338043D01*
X8128Y338127D01*
X8073Y338182D01*
X8045Y338210D01*
X8031Y338224D01*
Y339153D01*
X14244D01*
Y338016D01*
D02*
G37*
G36*
X20036Y415417D02*
X20189Y415195D01*
X20369Y414973D01*
X20536Y414779D01*
X20702Y414612D01*
X20827Y414474D01*
X20882Y414432D01*
X20924Y414390D01*
X20938Y414377D01*
X20952Y414363D01*
X21243Y414127D01*
X21534Y413905D01*
X21812Y413711D01*
X22089Y413558D01*
X22325Y413420D01*
X22422Y413364D01*
X22505Y413323D01*
X22574Y413281D01*
X22630Y413267D01*
X22658Y413239D01*
X22671D01*
Y412102D01*
X22464Y412185D01*
X22255Y412282D01*
X22047Y412379D01*
X21853Y412477D01*
X21687Y412560D01*
X21548Y412629D01*
X21465Y412685D01*
X21451Y412699D01*
X21437D01*
X21188Y412851D01*
X20966Y413004D01*
X20772Y413142D01*
X20619Y413267D01*
X20480Y413364D01*
X20397Y413447D01*
X20328Y413503D01*
X20314Y413517D01*
Y406014D01*
X19135D01*
Y415653D01*
X19898D01*
X20036Y415417D01*
D02*
G37*
G36*
X15904Y410549D02*
X14794Y410396D01*
X14697Y410549D01*
X14572Y410674D01*
X14461Y410798D01*
X14351Y410896D01*
X14239Y410965D01*
X14156Y411034D01*
X14101Y411062D01*
X14087Y411076D01*
X13907Y411159D01*
X13726Y411228D01*
X13560Y411270D01*
X13393Y411312D01*
X13255Y411325D01*
X13144Y411339D01*
X12880D01*
X12714Y411312D01*
X12423Y411242D01*
X12173Y411145D01*
X11951Y411048D01*
X11785Y410937D01*
X11660Y410840D01*
X11591Y410771D01*
X11563Y410757D01*
Y410743D01*
X11369Y410507D01*
X11230Y410258D01*
X11133Y409994D01*
X11064Y409731D01*
X11022Y409509D01*
X11008Y409412D01*
Y409328D01*
X10994Y409259D01*
Y409204D01*
Y409176D01*
Y409162D01*
Y408968D01*
X11022Y408788D01*
X11091Y408441D01*
X11188Y408150D01*
X11286Y407914D01*
X11396Y407720D01*
X11494Y407567D01*
X11535Y407526D01*
X11563Y407484D01*
X11577Y407470D01*
X11591Y407456D01*
X11702Y407345D01*
X11812Y407248D01*
X12062Y407082D01*
X12298Y406971D01*
X12534Y406902D01*
X12728Y406846D01*
X12894Y406832D01*
X12950Y406818D01*
X13033D01*
X13297Y406832D01*
X13532Y406888D01*
X13740Y406957D01*
X13907Y407040D01*
X14059Y407123D01*
X14170Y407193D01*
X14226Y407248D01*
X14253Y407262D01*
X14420Y407456D01*
X14559Y407664D01*
X14669Y407900D01*
X14753Y408108D01*
X14808Y408316D01*
X14850Y408469D01*
X14864Y408538D01*
X14878Y408580D01*
Y408607D01*
Y408621D01*
X16112Y408524D01*
X16084Y408302D01*
X16042Y408094D01*
X15918Y407706D01*
X15765Y407373D01*
X15682Y407220D01*
X15599Y407096D01*
X15529Y406971D01*
X15446Y406860D01*
X15377Y406777D01*
X15307Y406707D01*
X15252Y406652D01*
X15224Y406596D01*
X15196Y406582D01*
X15183Y406569D01*
X15016Y406444D01*
X14850Y406333D01*
X14669Y406236D01*
X14489Y406153D01*
X14142Y406028D01*
X13796Y405945D01*
X13643Y405903D01*
X13491Y405889D01*
X13366Y405875D01*
X13255Y405861D01*
X13158Y405848D01*
X13033D01*
X12742Y405861D01*
X12464Y405903D01*
X12201Y405959D01*
X11965Y406028D01*
X11743Y406125D01*
X11535Y406222D01*
X11341Y406319D01*
X11175Y406430D01*
X11022Y406541D01*
X10883Y406638D01*
X10772Y406749D01*
X10675Y406832D01*
X10606Y406902D01*
X10551Y406957D01*
X10523Y406999D01*
X10509Y407012D01*
X10370Y407193D01*
X10259Y407387D01*
X10148Y407567D01*
X10065Y407761D01*
X9926Y408136D01*
X9843Y408496D01*
X9815Y408649D01*
X9788Y408801D01*
X9774Y408926D01*
X9760Y409037D01*
X9746Y409134D01*
Y409204D01*
Y409245D01*
Y409259D01*
X9760Y409509D01*
X9788Y409744D01*
X9829Y409980D01*
X9885Y410188D01*
X9954Y410382D01*
X10023Y410577D01*
X10107Y410743D01*
X10176Y410896D01*
X10259Y411034D01*
X10343Y411159D01*
X10412Y411256D01*
X10481Y411353D01*
X10537Y411423D01*
X10578Y411464D01*
X10606Y411492D01*
X10620Y411506D01*
X10786Y411658D01*
X10953Y411797D01*
X11133Y411908D01*
X11313Y412005D01*
X11494Y412102D01*
X11674Y412172D01*
X12007Y412269D01*
X12159Y412310D01*
X12298Y412338D01*
X12423Y412352D01*
X12534Y412366D01*
X12617Y412379D01*
X12922D01*
X13088Y412352D01*
X13421Y412282D01*
X13726Y412185D01*
X14004Y412074D01*
X14226Y411964D01*
X14323Y411908D01*
X14406Y411866D01*
X14475Y411825D01*
X14517Y411797D01*
X14545Y411783D01*
X14559Y411769D01*
X14045Y414363D01*
X10204D01*
Y415486D01*
X14974D01*
X15904Y410549D01*
D02*
G37*
G36*
X32754Y406014D02*
X31478D01*
Y410271D01*
X29841D01*
X29689Y410258D01*
X29578D01*
X29481Y410244D01*
X29411Y410230D01*
X29356D01*
X29328Y410216D01*
X29314D01*
X29093Y410147D01*
X28995Y410105D01*
X28912Y410064D01*
X28829Y410022D01*
X28774Y409994D01*
X28746Y409980D01*
X28732Y409966D01*
X28621Y409883D01*
X28510Y409786D01*
X28302Y409578D01*
X28205Y409481D01*
X28136Y409398D01*
X28094Y409342D01*
X28080Y409328D01*
X27942Y409134D01*
X27789Y408926D01*
X27636Y408704D01*
X27484Y408496D01*
X27359Y408302D01*
X27262Y408150D01*
X27220Y408094D01*
X27193Y408053D01*
X27165Y408025D01*
Y408011D01*
X25903Y406014D01*
X24322D01*
X25972Y408621D01*
X26166Y408899D01*
X26347Y409148D01*
X26527Y409356D01*
X26679Y409550D01*
X26818Y409689D01*
X26929Y409800D01*
X26998Y409869D01*
X27026Y409897D01*
X27137Y409980D01*
X27262Y410077D01*
X27512Y410230D01*
X27622Y410285D01*
X27706Y410341D01*
X27761Y410369D01*
X27789Y410382D01*
X27539Y410424D01*
X27304Y410466D01*
X27095Y410535D01*
X26888Y410591D01*
X26707Y410660D01*
X26541Y410743D01*
X26388Y410812D01*
X26250Y410882D01*
X26139Y410965D01*
X26028Y411034D01*
X25944Y411090D01*
X25875Y411145D01*
X25820Y411187D01*
X25778Y411228D01*
X25764Y411242D01*
X25750Y411256D01*
X25639Y411395D01*
X25528Y411534D01*
X25362Y411825D01*
X25251Y412116D01*
X25168Y412393D01*
X25112Y412629D01*
X25099Y412726D01*
Y412823D01*
X25085Y412893D01*
Y412948D01*
Y412976D01*
Y412990D01*
X25099Y413281D01*
X25140Y413545D01*
X25209Y413794D01*
X25279Y414002D01*
X25362Y414182D01*
X25417Y414321D01*
X25473Y414404D01*
X25487Y414418D01*
Y414432D01*
X25653Y414654D01*
X25820Y414848D01*
X26000Y415014D01*
X26166Y415139D01*
X26319Y415236D01*
X26444Y415292D01*
X26527Y415334D01*
X26541Y415347D01*
X26555D01*
X26679Y415389D01*
X26832Y415431D01*
X27137Y415500D01*
X27470Y415541D01*
X27775Y415583D01*
X28066Y415597D01*
X28191D01*
X28302Y415611D01*
X32754D01*
Y406014D01*
D02*
G37*
G36*
X264220Y327375D02*
X264594Y327305D01*
X264913Y327194D01*
X265191Y327084D01*
X265315Y327014D01*
X265413Y326959D01*
X265510Y326903D01*
X265579Y326848D01*
X265634Y326806D01*
X265676Y326778D01*
X265704Y326764D01*
X265718Y326751D01*
X265981Y326487D01*
X266189Y326196D01*
X266356Y325891D01*
X266494Y325586D01*
X266577Y325322D01*
X266619Y325211D01*
X266647Y325114D01*
X266661Y325031D01*
X266674Y324976D01*
X266688Y324934D01*
Y324920D01*
X265510Y324712D01*
X265454Y325017D01*
X265371Y325281D01*
X265274Y325503D01*
X265177Y325683D01*
X265080Y325821D01*
X264996Y325919D01*
X264941Y325988D01*
X264927Y326002D01*
X264747Y326140D01*
X264553Y326251D01*
X264372Y326321D01*
X264192Y326376D01*
X264026Y326404D01*
X263901Y326432D01*
X263790D01*
X263540Y326418D01*
X263318Y326362D01*
X263124Y326293D01*
X262958Y326224D01*
X262833Y326140D01*
X262736Y326071D01*
X262667Y326016D01*
X262653Y326002D01*
X262500Y325835D01*
X262389Y325655D01*
X262320Y325475D01*
X262264Y325308D01*
X262237Y325156D01*
X262209Y325045D01*
Y324962D01*
Y324948D01*
Y324934D01*
Y324781D01*
X262237Y324643D01*
X262306Y324407D01*
X262403Y324199D01*
X262514Y324019D01*
X262625Y323894D01*
X262722Y323797D01*
X262791Y323741D01*
X262805Y323727D01*
X262819D01*
X263055Y323602D01*
X263277Y323505D01*
X263512Y323436D01*
X263721Y323395D01*
X263901Y323367D01*
X264053Y323339D01*
X264234D01*
X264289Y323353D01*
X264359D01*
X264497Y322313D01*
X264317Y322354D01*
X264151Y322382D01*
X264012Y322410D01*
X263887Y322424D01*
X263790Y322438D01*
X263665D01*
X263374Y322410D01*
X263110Y322354D01*
X262875Y322271D01*
X262680Y322174D01*
X262528Y322077D01*
X262417Y321994D01*
X262348Y321938D01*
X262320Y321911D01*
X262140Y321703D01*
X262001Y321481D01*
X261904Y321259D01*
X261848Y321037D01*
X261807Y320857D01*
X261793Y320704D01*
X261779Y320649D01*
Y320607D01*
Y320579D01*
Y320565D01*
X261807Y320260D01*
X261876Y319983D01*
X261959Y319747D01*
X262070Y319539D01*
X262181Y319373D01*
X262264Y319248D01*
X262334Y319165D01*
X262362Y319137D01*
X262583Y318943D01*
X262819Y318804D01*
X263055Y318707D01*
X263277Y318638D01*
X263471Y318596D01*
X263624Y318582D01*
X263679Y318568D01*
X263762D01*
X264012Y318582D01*
X264248Y318638D01*
X264456Y318707D01*
X264622Y318790D01*
X264761Y318860D01*
X264872Y318929D01*
X264927Y318984D01*
X264955Y318998D01*
X265121Y319192D01*
X265260Y319414D01*
X265385Y319650D01*
X265482Y319900D01*
X265551Y320108D01*
X265579Y320205D01*
X265593Y320288D01*
X265607Y320357D01*
X265620Y320413D01*
X265634Y320440D01*
Y320454D01*
X266813Y320302D01*
X266786Y320080D01*
X266744Y319872D01*
X266619Y319484D01*
X266467Y319151D01*
X266383Y319012D01*
X266300Y318873D01*
X266217Y318749D01*
X266134Y318652D01*
X266064Y318554D01*
X265995Y318485D01*
X265953Y318430D01*
X265912Y318388D01*
X265884Y318360D01*
X265870Y318346D01*
X265704Y318222D01*
X265537Y318097D01*
X265371Y318000D01*
X265191Y317917D01*
X264844Y317778D01*
X264511Y317695D01*
X264359Y317667D01*
X264220Y317639D01*
X264095Y317625D01*
X263984Y317611D01*
X263901Y317598D01*
X263776D01*
X263512Y317611D01*
X263277Y317639D01*
X263041Y317681D01*
X262819Y317736D01*
X262611Y317806D01*
X262431Y317875D01*
X262250Y317958D01*
X262098Y318041D01*
X261945Y318111D01*
X261821Y318194D01*
X261710Y318263D01*
X261626Y318333D01*
X261557Y318388D01*
X261502Y318430D01*
X261474Y318457D01*
X261460Y318471D01*
X261294Y318638D01*
X261155Y318818D01*
X261030Y318998D01*
X260919Y319179D01*
X260836Y319345D01*
X260753Y319525D01*
X260642Y319858D01*
X260614Y320011D01*
X260586Y320149D01*
X260559Y320274D01*
X260545Y320385D01*
X260531Y320468D01*
Y320538D01*
Y320579D01*
Y320593D01*
X260545Y320926D01*
X260600Y321231D01*
X260683Y321494D01*
X260767Y321716D01*
X260850Y321897D01*
X260933Y322035D01*
X260989Y322119D01*
X261002Y322146D01*
X261196Y322354D01*
X261404Y322535D01*
X261626Y322673D01*
X261848Y322784D01*
X262043Y322868D01*
X262195Y322923D01*
X262250Y322937D01*
X262292Y322951D01*
X262320Y322965D01*
X262334D01*
X262098Y323089D01*
X261904Y323214D01*
X261737Y323353D01*
X261599Y323478D01*
X261488Y323589D01*
X261404Y323686D01*
X261363Y323741D01*
X261349Y323769D01*
X261238Y323963D01*
X261155Y324157D01*
X261086Y324351D01*
X261044Y324532D01*
X261016Y324684D01*
X261002Y324795D01*
Y324878D01*
Y324906D01*
X261016Y325142D01*
X261058Y325378D01*
X261113Y325586D01*
X261183Y325766D01*
X261252Y325919D01*
X261308Y326043D01*
X261349Y326113D01*
X261363Y326140D01*
X261502Y326348D01*
X261668Y326529D01*
X261835Y326681D01*
X262001Y326820D01*
X262140Y326917D01*
X262264Y327000D01*
X262348Y327042D01*
X262362Y327056D01*
X262375D01*
X262625Y327167D01*
X262875Y327250D01*
X263124Y327319D01*
X263346Y327361D01*
X263526Y327389D01*
X263679Y327402D01*
X264026D01*
X264220Y327375D01*
D02*
G37*
G36*
X271362Y327389D02*
X271598Y327375D01*
X271820Y327333D01*
X272028Y327291D01*
X272222Y327236D01*
X272402Y327181D01*
X272569Y327111D01*
X272721Y327042D01*
X272860Y326973D01*
X272971Y326903D01*
X273068Y326848D01*
X273151Y326792D01*
X273220Y326751D01*
X273262Y326709D01*
X273290Y326695D01*
X273304Y326681D01*
X273442Y326543D01*
X273567Y326390D01*
X273692Y326224D01*
X273789Y326057D01*
X273955Y325724D01*
X274066Y325392D01*
X274108Y325239D01*
X274150Y325086D01*
X274177Y324962D01*
X274205Y324851D01*
X274219Y324754D01*
Y324684D01*
X274233Y324643D01*
Y324629D01*
X273026Y324504D01*
X272999Y324823D01*
X272943Y325100D01*
X272860Y325350D01*
X272763Y325544D01*
X272680Y325710D01*
X272596Y325821D01*
X272541Y325891D01*
X272513Y325919D01*
X272305Y326085D01*
X272083Y326210D01*
X271847Y326307D01*
X271639Y326362D01*
X271445Y326404D01*
X271279Y326418D01*
X271223Y326432D01*
X271140D01*
X270849Y326418D01*
X270585Y326362D01*
X270364Y326279D01*
X270169Y326196D01*
X270017Y326099D01*
X269920Y326030D01*
X269850Y325974D01*
X269823Y325946D01*
X269656Y325752D01*
X269531Y325558D01*
X269434Y325364D01*
X269379Y325170D01*
X269337Y325017D01*
X269323Y324878D01*
X269310Y324795D01*
Y324781D01*
Y324767D01*
X269337Y324518D01*
X269393Y324254D01*
X269490Y324019D01*
X269587Y323797D01*
X269698Y323616D01*
X269795Y323464D01*
X269823Y323408D01*
X269850Y323367D01*
X269878Y323353D01*
Y323339D01*
X269989Y323186D01*
X270128Y323034D01*
X270280Y322868D01*
X270447Y322701D01*
X270793Y322368D01*
X271140Y322035D01*
X271320Y321883D01*
X271473Y321744D01*
X271625Y321619D01*
X271750Y321508D01*
X271847Y321425D01*
X271931Y321356D01*
X271986Y321314D01*
X272000Y321300D01*
X272347Y321009D01*
X272666Y320732D01*
X272929Y320482D01*
X273137Y320274D01*
X273318Y320094D01*
X273442Y319969D01*
X273512Y319886D01*
X273539Y319872D01*
Y319858D01*
X273734Y319622D01*
X273886Y319400D01*
X274025Y319179D01*
X274136Y318984D01*
X274219Y318818D01*
X274274Y318693D01*
X274302Y318610D01*
X274316Y318596D01*
Y318582D01*
X274371Y318430D01*
X274399Y318291D01*
X274427Y318152D01*
X274441Y318027D01*
X274455Y317917D01*
Y317833D01*
Y317778D01*
Y317764D01*
X268089D01*
Y318901D01*
X272818D01*
X272652Y319137D01*
X272569Y319234D01*
X272499Y319331D01*
X272430Y319414D01*
X272374Y319470D01*
X272333Y319511D01*
X272319Y319525D01*
X272250Y319595D01*
X272166Y319664D01*
X271972Y319844D01*
X271750Y320052D01*
X271515Y320260D01*
X271293Y320440D01*
X271196Y320524D01*
X271112Y320607D01*
X271043Y320662D01*
X270988Y320704D01*
X270960Y320732D01*
X270946Y320746D01*
X270724Y320940D01*
X270502Y321120D01*
X270308Y321300D01*
X270128Y321453D01*
X269961Y321605D01*
X269823Y321744D01*
X269684Y321869D01*
X269573Y321980D01*
X269462Y322091D01*
X269379Y322174D01*
X269310Y322243D01*
X269240Y322313D01*
X269171Y322396D01*
X269143Y322424D01*
X268949Y322659D01*
X268783Y322868D01*
X268644Y323075D01*
X268533Y323242D01*
X268450Y323395D01*
X268394Y323505D01*
X268367Y323575D01*
X268353Y323602D01*
X268269Y323811D01*
X268214Y324019D01*
X268158Y324213D01*
X268131Y324379D01*
X268117Y324532D01*
X268103Y324643D01*
Y324712D01*
Y324740D01*
X268117Y324948D01*
X268145Y325142D01*
X268172Y325336D01*
X268228Y325503D01*
X268367Y325835D01*
X268505Y326099D01*
X268588Y326224D01*
X268658Y326321D01*
X268727Y326418D01*
X268796Y326487D01*
X268852Y326543D01*
X268880Y326598D01*
X268907Y326612D01*
X268921Y326626D01*
X269074Y326764D01*
X269240Y326889D01*
X269421Y326986D01*
X269601Y327070D01*
X269961Y327208D01*
X270322Y327305D01*
X270474Y327333D01*
X270627Y327361D01*
X270766Y327375D01*
X270877Y327389D01*
X270974Y327402D01*
X271112D01*
X271362Y327389D01*
D02*
G37*
G36*
X283469Y317764D02*
X282193D01*
Y322021D01*
X280557D01*
X280404Y322008D01*
X280293D01*
X280196Y321994D01*
X280127Y321980D01*
X280071D01*
X280044Y321966D01*
X280030D01*
X279808Y321897D01*
X279711Y321855D01*
X279628Y321814D01*
X279544Y321772D01*
X279489Y321744D01*
X279461Y321730D01*
X279447Y321716D01*
X279336Y321633D01*
X279225Y321536D01*
X279017Y321328D01*
X278920Y321231D01*
X278851Y321148D01*
X278809Y321092D01*
X278796Y321078D01*
X278657Y320884D01*
X278504Y320676D01*
X278352Y320454D01*
X278199Y320246D01*
X278074Y320052D01*
X277977Y319900D01*
X277936Y319844D01*
X277908Y319803D01*
X277880Y319775D01*
Y319761D01*
X276618Y317764D01*
X275037D01*
X276688Y320371D01*
X276882Y320649D01*
X277062Y320898D01*
X277242Y321106D01*
X277395Y321300D01*
X277533Y321439D01*
X277644Y321550D01*
X277714Y321619D01*
X277742Y321647D01*
X277852Y321730D01*
X277977Y321827D01*
X278227Y321980D01*
X278338Y322035D01*
X278421Y322091D01*
X278477Y322119D01*
X278504Y322132D01*
X278255Y322174D01*
X278019Y322216D01*
X277811Y322285D01*
X277603Y322341D01*
X277423Y322410D01*
X277256Y322493D01*
X277104Y322562D01*
X276965Y322632D01*
X276854Y322715D01*
X276743Y322784D01*
X276660Y322840D01*
X276590Y322895D01*
X276535Y322937D01*
X276493Y322978D01*
X276479Y322992D01*
X276466Y323006D01*
X276355Y323145D01*
X276244Y323284D01*
X276077Y323575D01*
X275966Y323866D01*
X275883Y324143D01*
X275828Y324379D01*
X275814Y324476D01*
Y324573D01*
X275800Y324643D01*
Y324698D01*
Y324726D01*
Y324740D01*
X275814Y325031D01*
X275855Y325294D01*
X275925Y325544D01*
X275994Y325752D01*
X276077Y325932D01*
X276133Y326071D01*
X276188Y326154D01*
X276202Y326168D01*
Y326182D01*
X276369Y326404D01*
X276535Y326598D01*
X276715Y326764D01*
X276882Y326889D01*
X277034Y326986D01*
X277159Y327042D01*
X277242Y327084D01*
X277256Y327097D01*
X277270D01*
X277395Y327139D01*
X277547Y327181D01*
X277852Y327250D01*
X278185Y327291D01*
X278490Y327333D01*
X278782Y327347D01*
X278906D01*
X279017Y327361D01*
X283469D01*
Y317764D01*
D02*
G37*
G36*
X145146Y347627D02*
X145299Y347405D01*
X145479Y347183D01*
X145646Y346989D01*
X145812Y346822D01*
X145937Y346684D01*
X145992Y346642D01*
X146034Y346600D01*
X146048Y346587D01*
X146062Y346573D01*
X146353Y346337D01*
X146644Y346115D01*
X146922Y345921D01*
X147199Y345768D01*
X147435Y345630D01*
X147532Y345574D01*
X147615Y345533D01*
X147684Y345491D01*
X147740Y345477D01*
X147767Y345449D01*
X147781D01*
Y344312D01*
X147573Y344395D01*
X147365Y344492D01*
X147157Y344590D01*
X146963Y344687D01*
X146797Y344770D01*
X146658Y344839D01*
X146575Y344895D01*
X146561Y344908D01*
X146547D01*
X146297Y345061D01*
X146075Y345214D01*
X145881Y345352D01*
X145729Y345477D01*
X145590Y345574D01*
X145507Y345657D01*
X145438Y345713D01*
X145424Y345727D01*
Y338224D01*
X144245D01*
Y347863D01*
X145008D01*
X145146Y347627D01*
D02*
G37*
G36*
X138101Y347849D02*
X138365Y347821D01*
X138614Y347765D01*
X138850Y347696D01*
X139058Y347599D01*
X139266Y347516D01*
X139446Y347405D01*
X139613Y347308D01*
X139752Y347211D01*
X139890Y347100D01*
X140001Y347016D01*
X140084Y346933D01*
X140154Y346850D01*
X140209Y346795D01*
X140237Y346767D01*
X140251Y346753D01*
X140431Y346503D01*
X140584Y346212D01*
X140722Y345907D01*
X140847Y345588D01*
X140944Y345255D01*
X141027Y344922D01*
X141097Y344576D01*
X141152Y344257D01*
X141194Y343938D01*
X141222Y343647D01*
X141249Y343383D01*
X141263Y343161D01*
Y342967D01*
X141277Y342828D01*
Y342773D01*
Y342731D01*
Y342717D01*
Y342704D01*
X141263Y342260D01*
X141235Y341844D01*
X141194Y341455D01*
X141124Y341095D01*
X141055Y340776D01*
X140986Y340485D01*
X140903Y340221D01*
X140806Y339985D01*
X140722Y339791D01*
X140639Y339611D01*
X140570Y339472D01*
X140486Y339347D01*
X140431Y339250D01*
X140389Y339195D01*
X140362Y339153D01*
X140348Y339139D01*
X140168Y338945D01*
X139973Y338779D01*
X139779Y338640D01*
X139585Y338515D01*
X139377Y338404D01*
X139183Y338321D01*
X138989Y338252D01*
X138795Y338196D01*
X138628Y338155D01*
X138462Y338113D01*
X138323Y338085D01*
X138198Y338071D01*
X138087D01*
X138018Y338058D01*
X137949D01*
X137630Y338071D01*
X137338Y338127D01*
X137075Y338182D01*
X136839Y338266D01*
X136659Y338335D01*
X136520Y338404D01*
X136465Y338418D01*
X136423Y338446D01*
X136409Y338460D01*
X136395D01*
X136160Y338626D01*
X135938Y338820D01*
X135757Y339015D01*
X135605Y339209D01*
X135480Y339389D01*
X135397Y339528D01*
X135369Y339583D01*
X135341Y339625D01*
X135328Y339638D01*
Y339652D01*
X135189Y339944D01*
X135092Y340249D01*
X135022Y340526D01*
X134981Y340790D01*
X134939Y341012D01*
Y341095D01*
X134925Y341178D01*
Y341247D01*
Y341289D01*
Y341317D01*
Y341330D01*
X134939Y341580D01*
X134967Y341816D01*
X135008Y342052D01*
X135050Y342260D01*
X135119Y342454D01*
X135189Y342648D01*
X135258Y342814D01*
X135341Y342967D01*
X135425Y343106D01*
X135494Y343231D01*
X135563Y343327D01*
X135633Y343425D01*
X135674Y343494D01*
X135716Y343536D01*
X135744Y343563D01*
X135757Y343577D01*
X135910Y343730D01*
X136076Y343868D01*
X136257Y343979D01*
X136423Y344076D01*
X136589Y344174D01*
X136756Y344243D01*
X137075Y344340D01*
X137214Y344381D01*
X137352Y344409D01*
X137463Y344423D01*
X137574Y344437D01*
X137657Y344451D01*
X137768D01*
X138018Y344437D01*
X138254Y344395D01*
X138476Y344354D01*
X138670Y344298D01*
X138836Y344229D01*
X138961Y344187D01*
X139044Y344146D01*
X139058Y344132D01*
X139072D01*
X139294Y343993D01*
X139488Y343841D01*
X139668Y343688D01*
X139807Y343522D01*
X139932Y343383D01*
X140029Y343272D01*
X140084Y343189D01*
X140098Y343175D01*
Y343425D01*
X140084Y343674D01*
X140070Y343896D01*
X140043Y344118D01*
X140029Y344312D01*
X140001Y344492D01*
X139973Y344659D01*
X139932Y344812D01*
X139904Y344950D01*
X139876Y345061D01*
X139849Y345158D01*
X139835Y345241D01*
X139807Y345297D01*
X139793Y345339D01*
X139779Y345366D01*
Y345380D01*
X139641Y345657D01*
X139502Y345907D01*
X139349Y346101D01*
X139211Y346268D01*
X139086Y346406D01*
X138989Y346503D01*
X138919Y346559D01*
X138892Y346573D01*
X138725Y346684D01*
X138559Y346753D01*
X138392Y346809D01*
X138226Y346850D01*
X138101Y346878D01*
X137990Y346892D01*
X137893D01*
X137643Y346864D01*
X137408Y346809D01*
X137214Y346725D01*
X137033Y346642D01*
X136895Y346545D01*
X136798Y346462D01*
X136742Y346406D01*
X136714Y346379D01*
X136617Y346254D01*
X136520Y346101D01*
X136437Y345935D01*
X136382Y345768D01*
X136326Y345616D01*
X136284Y345491D01*
X136271Y345408D01*
X136257Y345394D01*
Y345380D01*
X135078Y345477D01*
X135161Y345866D01*
X135286Y346212D01*
X135425Y346517D01*
X135577Y346767D01*
X135730Y346961D01*
X135785Y347044D01*
X135855Y347114D01*
X135896Y347155D01*
X135938Y347197D01*
X135952Y347211D01*
X135965Y347225D01*
X136104Y347336D01*
X136257Y347433D01*
X136562Y347599D01*
X136867Y347710D01*
X137158Y347779D01*
X137422Y347835D01*
X137533Y347849D01*
X137630D01*
X137713Y347863D01*
X137824D01*
X138101Y347849D01*
D02*
G37*
G36*
X157864Y338224D02*
X156588D01*
Y342482D01*
X154951D01*
X154799Y342468D01*
X154688D01*
X154591Y342454D01*
X154521Y342440D01*
X154466D01*
X154438Y342426D01*
X154424D01*
X154202Y342357D01*
X154105Y342315D01*
X154022Y342273D01*
X153939Y342232D01*
X153883Y342204D01*
X153856Y342190D01*
X153842Y342177D01*
X153731Y342093D01*
X153620Y341996D01*
X153412Y341788D01*
X153315Y341691D01*
X153245Y341608D01*
X153204Y341552D01*
X153190Y341539D01*
X153051Y341344D01*
X152899Y341136D01*
X152746Y340914D01*
X152594Y340706D01*
X152469Y340512D01*
X152372Y340360D01*
X152330Y340304D01*
X152302Y340263D01*
X152275Y340235D01*
Y340221D01*
X151013Y338224D01*
X149432D01*
X151082Y340831D01*
X151276Y341109D01*
X151456Y341358D01*
X151637Y341566D01*
X151789Y341760D01*
X151928Y341899D01*
X152039Y342010D01*
X152108Y342079D01*
X152136Y342107D01*
X152247Y342190D01*
X152372Y342287D01*
X152621Y342440D01*
X152732Y342495D01*
X152816Y342551D01*
X152871Y342579D01*
X152899Y342593D01*
X152649Y342634D01*
X152413Y342676D01*
X152205Y342745D01*
X151997Y342800D01*
X151817Y342870D01*
X151651Y342953D01*
X151498Y343022D01*
X151359Y343092D01*
X151248Y343175D01*
X151138Y343244D01*
X151054Y343300D01*
X150985Y343355D01*
X150929Y343397D01*
X150888Y343438D01*
X150874Y343452D01*
X150860Y343466D01*
X150749Y343605D01*
X150638Y343744D01*
X150472Y344035D01*
X150361Y344326D01*
X150278Y344603D01*
X150222Y344839D01*
X150208Y344936D01*
Y345033D01*
X150194Y345103D01*
Y345158D01*
Y345186D01*
Y345200D01*
X150208Y345491D01*
X150250Y345755D01*
X150319Y346004D01*
X150389Y346212D01*
X150472Y346392D01*
X150527Y346531D01*
X150583Y346614D01*
X150597Y346628D01*
Y346642D01*
X150763Y346864D01*
X150929Y347058D01*
X151110Y347225D01*
X151276Y347349D01*
X151429Y347446D01*
X151553Y347502D01*
X151637Y347543D01*
X151651Y347557D01*
X151664D01*
X151789Y347599D01*
X151942Y347641D01*
X152247Y347710D01*
X152580Y347752D01*
X152885Y347793D01*
X153176Y347807D01*
X153301D01*
X153412Y347821D01*
X157864D01*
Y338224D01*
D02*
G37*
G36*
X275384Y388070D02*
X274275Y387917D01*
X274178Y388070D01*
X274053Y388195D01*
X273942Y388319D01*
X273831Y388416D01*
X273720Y388486D01*
X273637Y388555D01*
X273581Y388583D01*
X273568Y388597D01*
X273387Y388680D01*
X273207Y388749D01*
X273041Y388791D01*
X272874Y388833D01*
X272736Y388846D01*
X272624Y388860D01*
X272361D01*
X272195Y388833D01*
X271903Y388763D01*
X271654Y388666D01*
X271432Y388569D01*
X271265Y388458D01*
X271141Y388361D01*
X271071Y388292D01*
X271043Y388278D01*
Y388264D01*
X270849Y388028D01*
X270711Y387779D01*
X270614Y387515D01*
X270544Y387252D01*
X270503Y387030D01*
X270489Y386932D01*
Y386849D01*
X270475Y386780D01*
Y386725D01*
Y386697D01*
Y386683D01*
Y386489D01*
X270503Y386308D01*
X270572Y385962D01*
X270669Y385671D01*
X270766Y385435D01*
X270877Y385241D01*
X270974Y385088D01*
X271016Y385046D01*
X271043Y385005D01*
X271057Y384991D01*
X271071Y384977D01*
X271182Y384866D01*
X271293Y384769D01*
X271543Y384603D01*
X271779Y384492D01*
X272014Y384422D01*
X272208Y384367D01*
X272375Y384353D01*
X272430Y384339D01*
X272514D01*
X272777Y384353D01*
X273013Y384408D01*
X273221Y384478D01*
X273387Y384561D01*
X273540Y384644D01*
X273651Y384714D01*
X273706Y384769D01*
X273734Y384783D01*
X273900Y384977D01*
X274039Y385185D01*
X274150Y385421D01*
X274233Y385629D01*
X274289Y385837D01*
X274330Y385989D01*
X274344Y386059D01*
X274358Y386100D01*
Y386128D01*
Y386142D01*
X275592Y386045D01*
X275565Y385823D01*
X275523Y385615D01*
X275398Y385227D01*
X275246Y384894D01*
X275162Y384741D01*
X275079Y384617D01*
X275010Y384492D01*
X274927Y384381D01*
X274857Y384297D01*
X274788Y384228D01*
X274732Y384173D01*
X274705Y384117D01*
X274677Y384103D01*
X274663Y384090D01*
X274497Y383965D01*
X274330Y383854D01*
X274150Y383757D01*
X273970Y383673D01*
X273623Y383549D01*
X273276Y383465D01*
X273124Y383424D01*
X272971Y383410D01*
X272846Y383396D01*
X272736Y383382D01*
X272638Y383368D01*
X272514D01*
X272222Y383382D01*
X271945Y383424D01*
X271681Y383479D01*
X271446Y383549D01*
X271224Y383646D01*
X271016Y383743D01*
X270822Y383840D01*
X270655Y383951D01*
X270503Y384062D01*
X270364Y384159D01*
X270253Y384270D01*
X270156Y384353D01*
X270087Y384422D01*
X270031Y384478D01*
X270003Y384519D01*
X269989Y384533D01*
X269851Y384714D01*
X269740Y384908D01*
X269629Y385088D01*
X269546Y385282D01*
X269407Y385657D01*
X269324Y386017D01*
X269296Y386170D01*
X269268Y386322D01*
X269254Y386447D01*
X269241Y386558D01*
X269227Y386655D01*
Y386725D01*
Y386766D01*
Y386780D01*
X269241Y387030D01*
X269268Y387265D01*
X269310Y387501D01*
X269366Y387709D01*
X269435Y387903D01*
X269504Y388097D01*
X269587Y388264D01*
X269657Y388416D01*
X269740Y388555D01*
X269823Y388680D01*
X269892Y388777D01*
X269962Y388874D01*
X270017Y388943D01*
X270059Y388985D01*
X270087Y389013D01*
X270100Y389027D01*
X270267Y389179D01*
X270433Y389318D01*
X270614Y389429D01*
X270794Y389526D01*
X270974Y389623D01*
X271154Y389692D01*
X271487Y389789D01*
X271640Y389831D01*
X271779Y389859D01*
X271903Y389873D01*
X272014Y389887D01*
X272097Y389900D01*
X272403D01*
X272569Y389873D01*
X272902Y389803D01*
X273207Y389706D01*
X273484Y389595D01*
X273706Y389484D01*
X273803Y389429D01*
X273887Y389387D01*
X273956Y389346D01*
X273997Y389318D01*
X274025Y389304D01*
X274039Y389290D01*
X273526Y391884D01*
X269684D01*
Y393007D01*
X274455D01*
X275384Y388070D01*
D02*
G37*
G36*
X284773Y387584D02*
Y387307D01*
X284759Y387043D01*
X284746Y386794D01*
X284718Y386558D01*
X284690Y386350D01*
X284662Y386156D01*
X284621Y385976D01*
X284593Y385809D01*
X284565Y385657D01*
X284524Y385532D01*
X284496Y385421D01*
X284468Y385338D01*
X284440Y385268D01*
X284426Y385213D01*
X284413Y385185D01*
Y385171D01*
X284260Y384866D01*
X284066Y384589D01*
X283872Y384367D01*
X283664Y384173D01*
X283484Y384020D01*
X283331Y383909D01*
X283276Y383881D01*
X283234Y383854D01*
X283206Y383826D01*
X283192D01*
X282845Y383673D01*
X282485Y383563D01*
X282111Y383479D01*
X281764Y383424D01*
X281611Y383410D01*
X281459Y383396D01*
X281320Y383382D01*
X281209D01*
X281112Y383368D01*
X280987D01*
X280488Y383396D01*
X280266Y383424D01*
X280058Y383451D01*
X279850Y383493D01*
X279670Y383535D01*
X279503Y383576D01*
X279351Y383632D01*
X279212Y383687D01*
X279101Y383729D01*
X278990Y383770D01*
X278907Y383812D01*
X278838Y383854D01*
X278796Y383868D01*
X278768Y383895D01*
X278754D01*
X278449Y384103D01*
X278200Y384339D01*
X278006Y384561D01*
X277839Y384783D01*
X277714Y384977D01*
X277631Y385130D01*
X277603Y385185D01*
X277575Y385227D01*
X277562Y385254D01*
Y385268D01*
X277506Y385435D01*
X277451Y385615D01*
X277367Y385989D01*
X277312Y386378D01*
X277270Y386752D01*
X277257Y386919D01*
X277243Y387085D01*
Y387224D01*
X277229Y387349D01*
Y387446D01*
Y387515D01*
Y387570D01*
Y387584D01*
Y393132D01*
X278505D01*
Y387584D01*
Y387265D01*
X278533Y386960D01*
X278560Y386697D01*
X278602Y386447D01*
X278643Y386225D01*
X278699Y386017D01*
X278741Y385837D01*
X278796Y385684D01*
X278851Y385560D01*
X278907Y385435D01*
X278962Y385351D01*
X279004Y385268D01*
X279046Y385213D01*
X279073Y385171D01*
X279087Y385157D01*
X279101Y385144D01*
X279226Y385033D01*
X279365Y384935D01*
X279670Y384783D01*
X279989Y384672D01*
X280322Y384603D01*
X280627Y384547D01*
X280751Y384533D01*
X280876D01*
X280959Y384519D01*
X281098D01*
X281389Y384533D01*
X281653Y384575D01*
X281903Y384617D01*
X282097Y384686D01*
X282263Y384741D01*
X282388Y384783D01*
X282457Y384824D01*
X282485Y384838D01*
X282679Y384963D01*
X282845Y385116D01*
X282984Y385268D01*
X283081Y385407D01*
X283165Y385546D01*
X283234Y385643D01*
X283262Y385712D01*
X283276Y385740D01*
X283317Y385865D01*
X283345Y385989D01*
X283400Y386281D01*
X283442Y386586D01*
X283470Y386891D01*
X283484Y387154D01*
Y387279D01*
X283497Y387376D01*
Y387459D01*
Y387529D01*
Y387570D01*
Y387584D01*
Y393132D01*
X284773D01*
Y387584D01*
D02*
G37*
G36*
X56231Y334084D02*
X56384Y333862D01*
X56564Y333640D01*
X56730Y333446D01*
X56897Y333279D01*
X57022Y333140D01*
X57077Y333099D01*
X57119Y333057D01*
X57133Y333043D01*
X57146Y333030D01*
X57438Y332794D01*
X57729Y332572D01*
X58006Y332378D01*
X58284Y332225D01*
X58519Y332086D01*
X58616Y332031D01*
X58700Y331989D01*
X58769Y331948D01*
X58824Y331934D01*
X58852Y331906D01*
X58866D01*
Y330769D01*
X58658Y330852D01*
X58450Y330949D01*
X58242Y331046D01*
X58048Y331143D01*
X57881Y331227D01*
X57743Y331296D01*
X57660Y331351D01*
X57646Y331365D01*
X57632D01*
X57382Y331518D01*
X57160Y331670D01*
X56966Y331809D01*
X56814Y331934D01*
X56675Y332031D01*
X56592Y332114D01*
X56522Y332170D01*
X56508Y332183D01*
Y324681D01*
X55330D01*
Y334319D01*
X56092D01*
X56231Y334084D01*
D02*
G37*
G36*
X68948Y324681D02*
X67673D01*
Y328938D01*
X66036D01*
X65883Y328924D01*
X65773D01*
X65675Y328911D01*
X65606Y328897D01*
X65551D01*
X65523Y328883D01*
X65509D01*
X65287Y328814D01*
X65190Y328772D01*
X65107Y328730D01*
X65024Y328689D01*
X64968Y328661D01*
X64940Y328647D01*
X64927Y328633D01*
X64816Y328550D01*
X64705Y328453D01*
X64497Y328245D01*
X64399Y328148D01*
X64330Y328065D01*
X64289Y328009D01*
X64275Y327995D01*
X64136Y327801D01*
X63983Y327593D01*
X63831Y327371D01*
X63678Y327163D01*
X63554Y326969D01*
X63457Y326816D01*
X63415Y326761D01*
X63387Y326719D01*
X63359Y326692D01*
Y326678D01*
X62097Y324681D01*
X60516D01*
X62167Y327288D01*
X62361Y327565D01*
X62541Y327815D01*
X62722Y328023D01*
X62874Y328217D01*
X63013Y328356D01*
X63124Y328467D01*
X63193Y328536D01*
X63221Y328564D01*
X63332Y328647D01*
X63457Y328744D01*
X63706Y328897D01*
X63817Y328952D01*
X63900Y329008D01*
X63956Y329035D01*
X63983Y329049D01*
X63734Y329091D01*
X63498Y329132D01*
X63290Y329202D01*
X63082Y329257D01*
X62902Y329327D01*
X62735Y329410D01*
X62583Y329479D01*
X62444Y329548D01*
X62333Y329632D01*
X62222Y329701D01*
X62139Y329757D01*
X62070Y329812D01*
X62014Y329854D01*
X61973Y329895D01*
X61959Y329909D01*
X61945Y329923D01*
X61834Y330062D01*
X61723Y330200D01*
X61557Y330492D01*
X61446Y330783D01*
X61362Y331060D01*
X61307Y331296D01*
X61293Y331393D01*
Y331490D01*
X61279Y331559D01*
Y331615D01*
Y331643D01*
Y331656D01*
X61293Y331948D01*
X61335Y332211D01*
X61404Y332461D01*
X61473Y332669D01*
X61557Y332849D01*
X61612Y332988D01*
X61667Y333071D01*
X61681Y333085D01*
Y333099D01*
X61848Y333321D01*
X62014Y333515D01*
X62194Y333681D01*
X62361Y333806D01*
X62513Y333903D01*
X62638Y333959D01*
X62722Y334000D01*
X62735Y334014D01*
X62749D01*
X62874Y334056D01*
X63027Y334097D01*
X63332Y334167D01*
X63664Y334208D01*
X63970Y334250D01*
X64261Y334264D01*
X64386D01*
X64497Y334278D01*
X68948D01*
Y324681D01*
D02*
G37*
G36*
X52709Y328065D02*
Y326983D01*
X48534D01*
Y324681D01*
X47355D01*
Y326983D01*
X46052D01*
Y328065D01*
X47355D01*
Y334278D01*
X48312D01*
X52709Y328065D01*
D02*
G37*
G36*
X49720Y321875D02*
X50094Y321805D01*
X50413Y321694D01*
X50691Y321584D01*
X50815Y321514D01*
X50912Y321459D01*
X51010Y321403D01*
X51079Y321348D01*
X51134Y321306D01*
X51176Y321278D01*
X51204Y321264D01*
X51218Y321251D01*
X51481Y320987D01*
X51689Y320696D01*
X51856Y320391D01*
X51994Y320086D01*
X52077Y319822D01*
X52119Y319711D01*
X52147Y319614D01*
X52161Y319531D01*
X52175Y319475D01*
X52188Y319434D01*
Y319420D01*
X51010Y319212D01*
X50954Y319517D01*
X50871Y319781D01*
X50774Y320003D01*
X50677Y320183D01*
X50580Y320322D01*
X50497Y320419D01*
X50441Y320488D01*
X50427Y320502D01*
X50247Y320640D01*
X50053Y320751D01*
X49872Y320821D01*
X49692Y320876D01*
X49526Y320904D01*
X49401Y320932D01*
X49290D01*
X49040Y320918D01*
X48818Y320862D01*
X48624Y320793D01*
X48458Y320724D01*
X48333Y320640D01*
X48236Y320571D01*
X48167Y320516D01*
X48153Y320502D01*
X48000Y320335D01*
X47889Y320155D01*
X47820Y319975D01*
X47764Y319808D01*
X47737Y319656D01*
X47709Y319545D01*
Y319462D01*
Y319448D01*
Y319434D01*
Y319281D01*
X47737Y319143D01*
X47806Y318907D01*
X47903Y318699D01*
X48014Y318519D01*
X48125Y318394D01*
X48222Y318297D01*
X48291Y318241D01*
X48305Y318227D01*
X48319D01*
X48555Y318102D01*
X48777Y318006D01*
X49013Y317936D01*
X49221Y317894D01*
X49401Y317867D01*
X49553Y317839D01*
X49734D01*
X49789Y317853D01*
X49858D01*
X49997Y316813D01*
X49817Y316854D01*
X49651Y316882D01*
X49512Y316910D01*
X49387Y316924D01*
X49290Y316938D01*
X49165D01*
X48874Y316910D01*
X48610Y316854D01*
X48375Y316771D01*
X48180Y316674D01*
X48028Y316577D01*
X47917Y316494D01*
X47848Y316438D01*
X47820Y316411D01*
X47640Y316203D01*
X47501Y315981D01*
X47404Y315759D01*
X47348Y315537D01*
X47307Y315357D01*
X47293Y315204D01*
X47279Y315149D01*
Y315107D01*
Y315079D01*
Y315065D01*
X47307Y314760D01*
X47376Y314483D01*
X47459Y314247D01*
X47570Y314039D01*
X47681Y313873D01*
X47764Y313748D01*
X47834Y313665D01*
X47861Y313637D01*
X48083Y313443D01*
X48319Y313304D01*
X48555Y313207D01*
X48777Y313138D01*
X48971Y313096D01*
X49124Y313082D01*
X49179Y313068D01*
X49262D01*
X49512Y313082D01*
X49748Y313138D01*
X49956Y313207D01*
X50122Y313290D01*
X50261Y313360D01*
X50372Y313429D01*
X50427Y313484D01*
X50455Y313498D01*
X50621Y313692D01*
X50760Y313914D01*
X50885Y314150D01*
X50982Y314400D01*
X51051Y314608D01*
X51079Y314705D01*
X51093Y314788D01*
X51107Y314857D01*
X51121Y314913D01*
X51134Y314940D01*
Y314954D01*
X52313Y314802D01*
X52285Y314580D01*
X52244Y314372D01*
X52119Y313984D01*
X51967Y313651D01*
X51883Y313512D01*
X51800Y313373D01*
X51717Y313249D01*
X51634Y313151D01*
X51564Y313054D01*
X51495Y312985D01*
X51453Y312930D01*
X51412Y312888D01*
X51384Y312860D01*
X51370Y312846D01*
X51204Y312722D01*
X51037Y312597D01*
X50871Y312500D01*
X50691Y312416D01*
X50344Y312278D01*
X50011Y312195D01*
X49858Y312167D01*
X49720Y312139D01*
X49595Y312125D01*
X49484Y312111D01*
X49401Y312097D01*
X49276D01*
X49013Y312111D01*
X48777Y312139D01*
X48541Y312181D01*
X48319Y312236D01*
X48111Y312306D01*
X47931Y312375D01*
X47751Y312458D01*
X47598Y312541D01*
X47445Y312611D01*
X47321Y312694D01*
X47210Y312763D01*
X47126Y312833D01*
X47057Y312888D01*
X47002Y312930D01*
X46974Y312957D01*
X46960Y312971D01*
X46794Y313138D01*
X46655Y313318D01*
X46530Y313498D01*
X46419Y313678D01*
X46336Y313845D01*
X46253Y314025D01*
X46142Y314358D01*
X46114Y314511D01*
X46086Y314649D01*
X46059Y314774D01*
X46045Y314885D01*
X46031Y314968D01*
Y315038D01*
Y315079D01*
Y315093D01*
X46045Y315426D01*
X46100Y315731D01*
X46183Y315994D01*
X46267Y316216D01*
X46350Y316397D01*
X46433Y316535D01*
X46488Y316619D01*
X46502Y316646D01*
X46697Y316854D01*
X46905Y317035D01*
X47126Y317173D01*
X47348Y317284D01*
X47543Y317367D01*
X47695Y317423D01*
X47751Y317437D01*
X47792Y317451D01*
X47820Y317465D01*
X47834D01*
X47598Y317589D01*
X47404Y317714D01*
X47237Y317853D01*
X47099Y317978D01*
X46988Y318089D01*
X46905Y318186D01*
X46863Y318241D01*
X46849Y318269D01*
X46738Y318463D01*
X46655Y318657D01*
X46586Y318851D01*
X46544Y319032D01*
X46516Y319184D01*
X46502Y319295D01*
Y319378D01*
Y319406D01*
X46516Y319642D01*
X46558Y319878D01*
X46613Y320086D01*
X46683Y320266D01*
X46752Y320419D01*
X46807Y320543D01*
X46849Y320613D01*
X46863Y320640D01*
X47002Y320849D01*
X47168Y321029D01*
X47334Y321181D01*
X47501Y321320D01*
X47640Y321417D01*
X47764Y321500D01*
X47848Y321542D01*
X47861Y321556D01*
X47875D01*
X48125Y321667D01*
X48375Y321750D01*
X48624Y321819D01*
X48846Y321861D01*
X49026Y321889D01*
X49179Y321903D01*
X49526D01*
X49720Y321875D01*
D02*
G37*
G36*
X56252Y321667D02*
X56404Y321445D01*
X56585Y321223D01*
X56751Y321029D01*
X56918Y320862D01*
X57042Y320724D01*
X57098Y320682D01*
X57139Y320640D01*
X57153Y320627D01*
X57167Y320613D01*
X57458Y320377D01*
X57750Y320155D01*
X58027Y319961D01*
X58304Y319808D01*
X58540Y319670D01*
X58637Y319614D01*
X58720Y319573D01*
X58790Y319531D01*
X58845Y319517D01*
X58873Y319489D01*
X58887D01*
Y318352D01*
X58679Y318435D01*
X58471Y318533D01*
X58263Y318629D01*
X58069Y318727D01*
X57902Y318810D01*
X57764Y318879D01*
X57680Y318935D01*
X57666Y318948D01*
X57653D01*
X57403Y319101D01*
X57181Y319254D01*
X56987Y319392D01*
X56834Y319517D01*
X56696Y319614D01*
X56612Y319697D01*
X56543Y319753D01*
X56529Y319767D01*
Y312264D01*
X55350D01*
Y321903D01*
X56113D01*
X56252Y321667D01*
D02*
G37*
G36*
X68969Y312264D02*
X67693D01*
Y316521D01*
X66057D01*
X65904Y316508D01*
X65793D01*
X65696Y316494D01*
X65627Y316480D01*
X65571D01*
X65544Y316466D01*
X65530D01*
X65308Y316397D01*
X65211Y316355D01*
X65128Y316313D01*
X65044Y316272D01*
X64989Y316244D01*
X64961Y316230D01*
X64947Y316216D01*
X64836Y316133D01*
X64725Y316036D01*
X64517Y315828D01*
X64420Y315731D01*
X64351Y315648D01*
X64309Y315592D01*
X64296Y315578D01*
X64157Y315384D01*
X64004Y315176D01*
X63852Y314954D01*
X63699Y314746D01*
X63574Y314552D01*
X63477Y314400D01*
X63436Y314344D01*
X63408Y314303D01*
X63380Y314275D01*
Y314261D01*
X62118Y312264D01*
X60537D01*
X62188Y314871D01*
X62382Y315149D01*
X62562Y315398D01*
X62742Y315606D01*
X62895Y315800D01*
X63033Y315939D01*
X63144Y316050D01*
X63214Y316119D01*
X63242Y316147D01*
X63352Y316230D01*
X63477Y316327D01*
X63727Y316480D01*
X63838Y316535D01*
X63921Y316591D01*
X63977Y316619D01*
X64004Y316632D01*
X63755Y316674D01*
X63519Y316716D01*
X63311Y316785D01*
X63103Y316840D01*
X62923Y316910D01*
X62756Y316993D01*
X62604Y317062D01*
X62465Y317132D01*
X62354Y317215D01*
X62243Y317284D01*
X62160Y317340D01*
X62091Y317395D01*
X62035Y317437D01*
X61993Y317479D01*
X61979Y317492D01*
X61966Y317506D01*
X61855Y317645D01*
X61744Y317784D01*
X61577Y318075D01*
X61466Y318366D01*
X61383Y318643D01*
X61328Y318879D01*
X61314Y318976D01*
Y319073D01*
X61300Y319143D01*
Y319198D01*
Y319226D01*
Y319240D01*
X61314Y319531D01*
X61355Y319795D01*
X61425Y320044D01*
X61494Y320252D01*
X61577Y320432D01*
X61633Y320571D01*
X61688Y320654D01*
X61702Y320668D01*
Y320682D01*
X61869Y320904D01*
X62035Y321098D01*
X62215Y321264D01*
X62382Y321389D01*
X62534Y321486D01*
X62659Y321542D01*
X62742Y321584D01*
X62756Y321597D01*
X62770D01*
X62895Y321639D01*
X63047Y321681D01*
X63352Y321750D01*
X63685Y321791D01*
X63990Y321833D01*
X64282Y321847D01*
X64406D01*
X64517Y321861D01*
X68969D01*
Y312264D01*
D02*
G37*
G36*
X258358Y216397D02*
X258594Y216383D01*
X258815Y216341D01*
X259023Y216300D01*
X259218Y216244D01*
X259398Y216189D01*
X259564Y216119D01*
X259717Y216050D01*
X259855Y215981D01*
X259967Y215911D01*
X260064Y215856D01*
X260147Y215800D01*
X260216Y215759D01*
X260258Y215717D01*
X260285Y215703D01*
X260299Y215690D01*
X260438Y215551D01*
X260563Y215398D01*
X260688Y215232D01*
X260785Y215065D01*
X260951Y214732D01*
X261062Y214400D01*
X261104Y214247D01*
X261145Y214095D01*
X261173Y213970D01*
X261201Y213859D01*
X261215Y213762D01*
Y213692D01*
X261229Y213651D01*
Y213637D01*
X260022Y213512D01*
X259994Y213831D01*
X259939Y214109D01*
X259855Y214358D01*
X259758Y214552D01*
X259675Y214719D01*
X259592Y214830D01*
X259537Y214899D01*
X259509Y214927D01*
X259301Y215093D01*
X259079Y215218D01*
X258843Y215315D01*
X258635Y215371D01*
X258441Y215412D01*
X258274Y215426D01*
X258219Y215440D01*
X258136D01*
X257845Y215426D01*
X257581Y215371D01*
X257359Y215287D01*
X257165Y215204D01*
X257013Y215107D01*
X256915Y215038D01*
X256846Y214982D01*
X256818Y214954D01*
X256652Y214760D01*
X256527Y214566D01*
X256430Y214372D01*
X256375Y214178D01*
X256333Y214025D01*
X256319Y213887D01*
X256305Y213803D01*
Y213790D01*
Y213776D01*
X256333Y213526D01*
X256388Y213263D01*
X256486Y213027D01*
X256583Y212805D01*
X256693Y212624D01*
X256791Y212472D01*
X256818Y212416D01*
X256846Y212375D01*
X256874Y212361D01*
Y212347D01*
X256985Y212195D01*
X257124Y212042D01*
X257276Y211876D01*
X257442Y211709D01*
X257789Y211376D01*
X258136Y211043D01*
X258316Y210891D01*
X258469Y210752D01*
X258621Y210627D01*
X258746Y210516D01*
X258843Y210433D01*
X258926Y210364D01*
X258982Y210322D01*
X258996Y210308D01*
X259342Y210017D01*
X259661Y209740D01*
X259925Y209490D01*
X260133Y209282D01*
X260313Y209102D01*
X260438Y208977D01*
X260507Y208894D01*
X260535Y208880D01*
Y208866D01*
X260729Y208630D01*
X260882Y208409D01*
X261021Y208187D01*
X261131Y207992D01*
X261215Y207826D01*
X261270Y207701D01*
X261298Y207618D01*
X261312Y207604D01*
Y207590D01*
X261367Y207438D01*
X261395Y207299D01*
X261423Y207160D01*
X261437Y207036D01*
X261450Y206925D01*
Y206841D01*
Y206786D01*
Y206772D01*
X255085D01*
Y207909D01*
X259814D01*
X259648Y208145D01*
X259564Y208242D01*
X259495Y208339D01*
X259426Y208422D01*
X259370Y208478D01*
X259328Y208519D01*
X259315Y208533D01*
X259245Y208603D01*
X259162Y208672D01*
X258968Y208852D01*
X258746Y209060D01*
X258510Y209268D01*
X258288Y209449D01*
X258191Y209532D01*
X258108Y209615D01*
X258039Y209671D01*
X257983Y209712D01*
X257956Y209740D01*
X257942Y209754D01*
X257720Y209948D01*
X257498Y210128D01*
X257304Y210308D01*
X257124Y210461D01*
X256957Y210614D01*
X256818Y210752D01*
X256680Y210877D01*
X256569Y210988D01*
X256458Y211099D01*
X256375Y211182D01*
X256305Y211252D01*
X256236Y211321D01*
X256166Y211404D01*
X256139Y211432D01*
X255945Y211668D01*
X255778Y211876D01*
X255639Y212084D01*
X255529Y212250D01*
X255445Y212403D01*
X255390Y212514D01*
X255362Y212583D01*
X255348Y212611D01*
X255265Y212819D01*
X255210Y213027D01*
X255154Y213221D01*
X255126Y213387D01*
X255112Y213540D01*
X255099Y213651D01*
Y213720D01*
Y213748D01*
X255112Y213956D01*
X255140Y214150D01*
X255168Y214344D01*
X255224Y214511D01*
X255362Y214844D01*
X255501Y215107D01*
X255584Y215232D01*
X255653Y215329D01*
X255723Y215426D01*
X255792Y215495D01*
X255848Y215551D01*
X255875Y215606D01*
X255903Y215620D01*
X255917Y215634D01*
X256070Y215773D01*
X256236Y215898D01*
X256416Y215995D01*
X256597Y216078D01*
X256957Y216217D01*
X257318Y216313D01*
X257470Y216341D01*
X257623Y216369D01*
X257761Y216383D01*
X257872Y216397D01*
X257969Y216411D01*
X258108D01*
X258358Y216397D01*
D02*
G37*
G36*
X265209Y216175D02*
X265361Y215953D01*
X265542Y215731D01*
X265708Y215537D01*
X265874Y215371D01*
X265999Y215232D01*
X266055Y215190D01*
X266096Y215149D01*
X266110Y215135D01*
X266124Y215121D01*
X266415Y214885D01*
X266707Y214663D01*
X266984Y214469D01*
X267261Y214317D01*
X267497Y214178D01*
X267594Y214122D01*
X267677Y214081D01*
X267747Y214039D01*
X267802Y214025D01*
X267830Y213997D01*
X267844D01*
Y212860D01*
X267636Y212943D01*
X267428Y213041D01*
X267220Y213138D01*
X267026Y213235D01*
X266859Y213318D01*
X266720Y213387D01*
X266637Y213443D01*
X266623Y213457D01*
X266609D01*
X266360Y213609D01*
X266138Y213762D01*
X265944Y213900D01*
X265791Y214025D01*
X265653Y214122D01*
X265569Y214205D01*
X265500Y214261D01*
X265486Y214275D01*
Y206772D01*
X264307D01*
Y216411D01*
X265070D01*
X265209Y216175D01*
D02*
G37*
G36*
X277926Y206772D02*
X276650D01*
Y211030D01*
X275014D01*
X274861Y211016D01*
X274750D01*
X274653Y211002D01*
X274584Y210988D01*
X274528D01*
X274501Y210974D01*
X274487D01*
X274265Y210905D01*
X274168Y210863D01*
X274084Y210822D01*
X274001Y210780D01*
X273946Y210752D01*
X273918Y210738D01*
X273904Y210725D01*
X273793Y210641D01*
X273682Y210544D01*
X273474Y210336D01*
X273377Y210239D01*
X273308Y210156D01*
X273266Y210100D01*
X273252Y210087D01*
X273114Y209893D01*
X272961Y209684D01*
X272809Y209463D01*
X272656Y209254D01*
X272531Y209060D01*
X272434Y208908D01*
X272393Y208852D01*
X272365Y208811D01*
X272337Y208783D01*
Y208769D01*
X271075Y206772D01*
X269494D01*
X271144Y209379D01*
X271339Y209657D01*
X271519Y209906D01*
X271699Y210114D01*
X271852Y210308D01*
X271990Y210447D01*
X272101Y210558D01*
X272171Y210627D01*
X272198Y210655D01*
X272309Y210738D01*
X272434Y210835D01*
X272684Y210988D01*
X272795Y211043D01*
X272878Y211099D01*
X272933Y211127D01*
X272961Y211141D01*
X272712Y211182D01*
X272476Y211224D01*
X272268Y211293D01*
X272060Y211349D01*
X271879Y211418D01*
X271713Y211501D01*
X271560Y211570D01*
X271422Y211640D01*
X271311Y211723D01*
X271200Y211792D01*
X271117Y211848D01*
X271047Y211903D01*
X270992Y211945D01*
X270950Y211987D01*
X270936Y212001D01*
X270923Y212014D01*
X270812Y212153D01*
X270701Y212292D01*
X270534Y212583D01*
X270423Y212874D01*
X270340Y213151D01*
X270285Y213387D01*
X270271Y213484D01*
Y213582D01*
X270257Y213651D01*
Y213706D01*
Y213734D01*
Y213748D01*
X270271Y214039D01*
X270312Y214303D01*
X270382Y214552D01*
X270451Y214760D01*
X270534Y214941D01*
X270590Y215079D01*
X270645Y215163D01*
X270659Y215176D01*
Y215190D01*
X270825Y215412D01*
X270992Y215606D01*
X271172Y215773D01*
X271339Y215898D01*
X271491Y215995D01*
X271616Y216050D01*
X271699Y216092D01*
X271713Y216105D01*
X271727D01*
X271852Y216147D01*
X272004Y216189D01*
X272309Y216258D01*
X272642Y216300D01*
X272947Y216341D01*
X273239Y216355D01*
X273363D01*
X273474Y216369D01*
X277926D01*
Y206772D01*
D02*
G37*
G36*
X241078Y216175D02*
X241231Y215953D01*
X241411Y215731D01*
X241577Y215537D01*
X241744Y215371D01*
X241869Y215232D01*
X241924Y215190D01*
X241966Y215149D01*
X241980Y215135D01*
X241993Y215121D01*
X242285Y214885D01*
X242576Y214663D01*
X242853Y214469D01*
X243131Y214317D01*
X243366Y214178D01*
X243463Y214122D01*
X243547Y214081D01*
X243616Y214039D01*
X243671Y214025D01*
X243699Y213997D01*
X243713D01*
Y212860D01*
X243505Y212943D01*
X243297Y213041D01*
X243089Y213138D01*
X242895Y213235D01*
X242728Y213318D01*
X242590Y213387D01*
X242507Y213443D01*
X242493Y213457D01*
X242479D01*
X242229Y213609D01*
X242007Y213762D01*
X241813Y213900D01*
X241661Y214025D01*
X241522Y214122D01*
X241439Y214205D01*
X241369Y214261D01*
X241355Y214275D01*
Y206772D01*
X240177D01*
Y216411D01*
X240939D01*
X241078Y216175D01*
D02*
G37*
G36*
X233617D02*
X233769Y215953D01*
X233950Y215731D01*
X234116Y215537D01*
X234283Y215371D01*
X234407Y215232D01*
X234463Y215190D01*
X234505Y215149D01*
X234518Y215135D01*
X234532Y215121D01*
X234823Y214885D01*
X235115Y214663D01*
X235392Y214469D01*
X235669Y214317D01*
X235905Y214178D01*
X236002Y214122D01*
X236085Y214081D01*
X236155Y214039D01*
X236210Y214025D01*
X236238Y213997D01*
X236252D01*
Y212860D01*
X236044Y212943D01*
X235836Y213041D01*
X235628Y213138D01*
X235434Y213235D01*
X235267Y213318D01*
X235129Y213387D01*
X235045Y213443D01*
X235032Y213457D01*
X235018D01*
X234768Y213609D01*
X234546Y213762D01*
X234352Y213900D01*
X234199Y214025D01*
X234061Y214122D01*
X233978Y214205D01*
X233908Y214261D01*
X233894Y214275D01*
Y206772D01*
X232715D01*
Y216411D01*
X233478D01*
X233617Y216175D01*
D02*
G37*
G36*
X253795Y206772D02*
X252519D01*
Y211030D01*
X250883D01*
X250730Y211016D01*
X250620D01*
X250522Y211002D01*
X250453Y210988D01*
X250398D01*
X250370Y210974D01*
X250356D01*
X250134Y210905D01*
X250037Y210863D01*
X249954Y210822D01*
X249871Y210780D01*
X249815Y210752D01*
X249788Y210738D01*
X249774Y210725D01*
X249663Y210641D01*
X249552Y210544D01*
X249344Y210336D01*
X249247Y210239D01*
X249177Y210156D01*
X249136Y210100D01*
X249122Y210087D01*
X248983Y209893D01*
X248831Y209684D01*
X248678Y209463D01*
X248525Y209254D01*
X248401Y209060D01*
X248304Y208908D01*
X248262Y208852D01*
X248234Y208811D01*
X248207Y208783D01*
Y208769D01*
X246944Y206772D01*
X245363D01*
X247014Y209379D01*
X247208Y209657D01*
X247388Y209906D01*
X247568Y210114D01*
X247721Y210308D01*
X247860Y210447D01*
X247971Y210558D01*
X248040Y210627D01*
X248068Y210655D01*
X248179Y210738D01*
X248304Y210835D01*
X248553Y210988D01*
X248664Y211043D01*
X248747Y211099D01*
X248803Y211127D01*
X248831Y211141D01*
X248581Y211182D01*
X248345Y211224D01*
X248137Y211293D01*
X247929Y211349D01*
X247749Y211418D01*
X247582Y211501D01*
X247430Y211570D01*
X247291Y211640D01*
X247180Y211723D01*
X247069Y211792D01*
X246986Y211848D01*
X246917Y211903D01*
X246861Y211945D01*
X246820Y211987D01*
X246806Y212001D01*
X246792Y212014D01*
X246681Y212153D01*
X246570Y212292D01*
X246404Y212583D01*
X246293Y212874D01*
X246209Y213151D01*
X246154Y213387D01*
X246140Y213484D01*
Y213582D01*
X246126Y213651D01*
Y213706D01*
Y213734D01*
Y213748D01*
X246140Y214039D01*
X246182Y214303D01*
X246251Y214552D01*
X246320Y214760D01*
X246404Y214941D01*
X246459Y215079D01*
X246514Y215163D01*
X246528Y215176D01*
Y215190D01*
X246695Y215412D01*
X246861Y215606D01*
X247041Y215773D01*
X247208Y215898D01*
X247360Y215995D01*
X247485Y216050D01*
X247568Y216092D01*
X247582Y216105D01*
X247596D01*
X247721Y216147D01*
X247874Y216189D01*
X248179Y216258D01*
X248512Y216300D01*
X248817Y216341D01*
X249108Y216355D01*
X249233D01*
X249344Y216369D01*
X253795D01*
Y206772D01*
D02*
G37*
G36*
X218493Y216258D02*
X218646Y216036D01*
X218826Y215814D01*
X218993Y215620D01*
X219159Y215454D01*
X219284Y215315D01*
X219339Y215273D01*
X219381Y215232D01*
X219395Y215218D01*
X219409Y215204D01*
X219700Y214968D01*
X219991Y214746D01*
X220269Y214552D01*
X220546Y214400D01*
X220782Y214261D01*
X220879Y214205D01*
X220962Y214164D01*
X221031Y214122D01*
X221087Y214109D01*
X221115Y214081D01*
X221128D01*
Y212943D01*
X220920Y213027D01*
X220712Y213124D01*
X220504Y213221D01*
X220310Y213318D01*
X220144Y213401D01*
X220005Y213470D01*
X219922Y213526D01*
X219908Y213540D01*
X219894D01*
X219645Y213692D01*
X219423Y213845D01*
X219228Y213984D01*
X219076Y214109D01*
X218937Y214205D01*
X218854Y214289D01*
X218785Y214344D01*
X218771Y214358D01*
Y206855D01*
X217592D01*
Y216494D01*
X218355D01*
X218493Y216258D01*
D02*
G37*
G36*
X231211Y206855D02*
X229935D01*
Y211113D01*
X228298D01*
X228146Y211099D01*
X228035D01*
X227938Y211085D01*
X227868Y211071D01*
X227813D01*
X227785Y211057D01*
X227771D01*
X227549Y210988D01*
X227452Y210947D01*
X227369Y210905D01*
X227286Y210863D01*
X227230Y210835D01*
X227203Y210822D01*
X227189Y210808D01*
X227078Y210725D01*
X226967Y210627D01*
X226759Y210420D01*
X226662Y210322D01*
X226593Y210239D01*
X226551Y210184D01*
X226537Y210170D01*
X226398Y209976D01*
X226246Y209768D01*
X226093Y209546D01*
X225941Y209338D01*
X225816Y209144D01*
X225719Y208991D01*
X225677Y208936D01*
X225650Y208894D01*
X225622Y208866D01*
Y208852D01*
X224360Y206855D01*
X222779D01*
X224429Y209463D01*
X224623Y209740D01*
X224804Y209989D01*
X224984Y210198D01*
X225136Y210392D01*
X225275Y210530D01*
X225386Y210641D01*
X225455Y210711D01*
X225483Y210738D01*
X225594Y210822D01*
X225719Y210919D01*
X225968Y211071D01*
X226079Y211127D01*
X226163Y211182D01*
X226218Y211210D01*
X226246Y211224D01*
X225996Y211265D01*
X225760Y211307D01*
X225552Y211376D01*
X225344Y211432D01*
X225164Y211501D01*
X224998Y211584D01*
X224845Y211654D01*
X224706Y211723D01*
X224596Y211806D01*
X224485Y211876D01*
X224401Y211931D01*
X224332Y211987D01*
X224277Y212028D01*
X224235Y212070D01*
X224221Y212084D01*
X224207Y212097D01*
X224096Y212236D01*
X223985Y212375D01*
X223819Y212666D01*
X223708Y212957D01*
X223625Y213235D01*
X223569Y213470D01*
X223555Y213568D01*
Y213665D01*
X223542Y213734D01*
Y213790D01*
Y213817D01*
Y213831D01*
X223555Y214122D01*
X223597Y214386D01*
X223666Y214636D01*
X223736Y214844D01*
X223819Y215024D01*
X223874Y215163D01*
X223930Y215246D01*
X223944Y215259D01*
Y215273D01*
X224110Y215495D01*
X224277Y215690D01*
X224457Y215856D01*
X224623Y215981D01*
X224776Y216078D01*
X224901Y216133D01*
X224984Y216175D01*
X224998Y216189D01*
X225012D01*
X225136Y216230D01*
X225289Y216272D01*
X225594Y216341D01*
X225927Y216383D01*
X226232Y216425D01*
X226523Y216438D01*
X226648D01*
X226759Y216452D01*
X231211D01*
Y206855D01*
D02*
G37*
G36*
X211809Y216466D02*
X212156Y216411D01*
X212447Y216313D01*
X212696Y216217D01*
X212904Y216105D01*
X212988Y216064D01*
X213057Y216008D01*
X213113Y215981D01*
X213154Y215953D01*
X213168Y215925D01*
X213182D01*
X213431Y215703D01*
X213640Y215440D01*
X213820Y215176D01*
X213958Y214927D01*
X214069Y214691D01*
X214125Y214594D01*
X214153Y214497D01*
X214180Y214427D01*
X214208Y214372D01*
X214222Y214344D01*
Y214330D01*
X214277Y214122D01*
X214333Y213914D01*
X214416Y213457D01*
X214485Y212999D01*
X214527Y212569D01*
X214541Y212361D01*
X214555Y212181D01*
Y212014D01*
X214569Y211862D01*
Y211751D01*
Y211654D01*
Y211598D01*
Y211584D01*
X214555Y211099D01*
X214527Y210641D01*
X214485Y210225D01*
X214416Y209837D01*
X214347Y209476D01*
X214264Y209157D01*
X214180Y208866D01*
X214097Y208617D01*
X214014Y208395D01*
X213917Y208200D01*
X213848Y208034D01*
X213778Y207909D01*
X213709Y207798D01*
X213667Y207729D01*
X213640Y207687D01*
X213626Y207673D01*
X213473Y207507D01*
X213307Y207355D01*
X213126Y207216D01*
X212946Y207105D01*
X212766Y207008D01*
X212586Y206925D01*
X212405Y206869D01*
X212239Y206814D01*
X212072Y206772D01*
X211920Y206744D01*
X211781Y206717D01*
X211670Y206703D01*
X211573Y206689D01*
X211434D01*
X211060Y206717D01*
X210713Y206772D01*
X210422Y206869D01*
X210172Y206966D01*
X209964Y207063D01*
X209895Y207119D01*
X209826Y207160D01*
X209770Y207188D01*
X209729Y207216D01*
X209715Y207244D01*
X209701D01*
X209451Y207479D01*
X209243Y207729D01*
X209063Y208006D01*
X208924Y208256D01*
X208813Y208492D01*
X208758Y208589D01*
X208730Y208686D01*
X208702Y208755D01*
X208675Y208811D01*
X208661Y208839D01*
Y208852D01*
X208591Y209060D01*
X208536Y209268D01*
X208453Y209712D01*
X208383Y210170D01*
X208342Y210614D01*
X208328Y210808D01*
X208314Y210988D01*
Y211154D01*
X208300Y211307D01*
Y211418D01*
Y211515D01*
Y211570D01*
Y211584D01*
Y211848D01*
X208314Y212097D01*
Y212319D01*
X208328Y212541D01*
X208356Y212736D01*
X208370Y212930D01*
X208383Y213096D01*
X208411Y213249D01*
X208425Y213387D01*
X208453Y213512D01*
X208467Y213609D01*
X208480Y213692D01*
X208494Y213762D01*
X208508Y213803D01*
X208522Y213831D01*
Y213845D01*
X208605Y214150D01*
X208702Y214427D01*
X208813Y214663D01*
X208897Y214871D01*
X208994Y215051D01*
X209049Y215176D01*
X209104Y215246D01*
X209118Y215273D01*
X209271Y215481D01*
X209424Y215662D01*
X209590Y215814D01*
X209743Y215953D01*
X209881Y216050D01*
X209992Y216119D01*
X210061Y216161D01*
X210075Y216175D01*
X210089D01*
X210311Y216286D01*
X210547Y216355D01*
X210769Y216411D01*
X210977Y216452D01*
X211157Y216480D01*
X211310Y216494D01*
X211434D01*
X211809Y216466D01*
D02*
G37*
G36*
X289546Y203830D02*
X289768Y203802D01*
X289990Y203761D01*
X290184Y203705D01*
X290559Y203553D01*
X290725Y203483D01*
X290864Y203400D01*
X291003Y203303D01*
X291113Y203234D01*
X291224Y203150D01*
X291308Y203081D01*
X291377Y203026D01*
X291419Y202984D01*
X291446Y202956D01*
X291460Y202942D01*
X291613Y202776D01*
X291738Y202582D01*
X291862Y202402D01*
X291959Y202207D01*
X292043Y201999D01*
X292112Y201805D01*
X292209Y201445D01*
X292251Y201264D01*
X292278Y201112D01*
X292292Y200959D01*
X292306Y200834D01*
X292320Y200737D01*
Y200668D01*
Y200613D01*
Y200599D01*
X292306Y200335D01*
X292278Y200099D01*
X292251Y199864D01*
X292195Y199642D01*
X292126Y199447D01*
X292057Y199253D01*
X291987Y199087D01*
X291904Y198934D01*
X291835Y198796D01*
X291765Y198671D01*
X291696Y198574D01*
X291627Y198477D01*
X291571Y198407D01*
X291543Y198366D01*
X291516Y198338D01*
X291502Y198324D01*
X291349Y198172D01*
X291183Y198047D01*
X291016Y197922D01*
X290836Y197825D01*
X290670Y197742D01*
X290503Y197672D01*
X290184Y197575D01*
X290046Y197534D01*
X289907Y197506D01*
X289796Y197492D01*
X289685Y197478D01*
X289602Y197464D01*
X289491D01*
X289227Y197478D01*
X288978Y197520D01*
X288756Y197575D01*
X288548Y197645D01*
X288395Y197700D01*
X288270Y197756D01*
X288187Y197797D01*
X288160Y197811D01*
X287938Y197950D01*
X287743Y198102D01*
X287577Y198255D01*
X287438Y198393D01*
X287341Y198532D01*
X287258Y198629D01*
X287203Y198699D01*
X287189Y198726D01*
Y198615D01*
Y198546D01*
Y198505D01*
Y198491D01*
X287203Y198213D01*
X287216Y197950D01*
X287244Y197714D01*
X287272Y197492D01*
X287314Y197312D01*
X287341Y197173D01*
X287355Y197118D01*
Y197076D01*
X287369Y197062D01*
Y197048D01*
X287438Y196799D01*
X287508Y196577D01*
X287577Y196383D01*
X287646Y196216D01*
X287702Y196091D01*
X287757Y195994D01*
X287785Y195925D01*
X287799Y195911D01*
X287910Y195758D01*
X288021Y195634D01*
X288132Y195523D01*
X288243Y195426D01*
X288326Y195343D01*
X288409Y195287D01*
X288465Y195259D01*
X288479Y195245D01*
X288631Y195162D01*
X288797Y195107D01*
X288950Y195065D01*
X289103Y195037D01*
X289227Y195023D01*
X289324Y195010D01*
X289422D01*
X289643Y195023D01*
X289851Y195065D01*
X290032Y195121D01*
X290184Y195190D01*
X290295Y195245D01*
X290392Y195301D01*
X290448Y195343D01*
X290462Y195356D01*
X290600Y195509D01*
X290711Y195689D01*
X290808Y195883D01*
X290878Y196077D01*
X290933Y196244D01*
X290975Y196397D01*
X290989Y196452D01*
Y196480D01*
X291003Y196507D01*
Y196521D01*
X292140Y196424D01*
X292057Y196022D01*
X291946Y195675D01*
X291807Y195370D01*
X291668Y195121D01*
X291530Y194926D01*
X291460Y194843D01*
X291405Y194774D01*
X291363Y194732D01*
X291322Y194691D01*
X291308Y194677D01*
X291294Y194663D01*
X291155Y194552D01*
X291003Y194455D01*
X290697Y194302D01*
X290392Y194191D01*
X290101Y194122D01*
X289838Y194067D01*
X289727Y194053D01*
X289630D01*
X289560Y194039D01*
X289449D01*
X289061Y194067D01*
X288714Y194122D01*
X288395Y194219D01*
X288132Y194330D01*
X288021Y194372D01*
X287910Y194427D01*
X287827Y194483D01*
X287743Y194524D01*
X287688Y194552D01*
X287646Y194580D01*
X287619Y194607D01*
X287605D01*
X287327Y194843D01*
X287078Y195107D01*
X286884Y195384D01*
X286717Y195648D01*
X286579Y195883D01*
X286523Y195994D01*
X286481Y196077D01*
X286454Y196161D01*
X286426Y196216D01*
X286412Y196244D01*
Y196258D01*
X286343Y196466D01*
X286273Y196702D01*
X286176Y197173D01*
X286107Y197672D01*
X286065Y198144D01*
X286038Y198352D01*
X286024Y198560D01*
Y198740D01*
X286010Y198893D01*
Y199018D01*
Y199115D01*
Y199184D01*
Y199198D01*
Y199517D01*
X286024Y199822D01*
X286052Y200099D01*
X286079Y200363D01*
X286107Y200599D01*
X286135Y200821D01*
X286176Y201028D01*
X286218Y201209D01*
X286260Y201361D01*
X286287Y201500D01*
X286329Y201625D01*
X286357Y201722D01*
X286384Y201791D01*
X286412Y201847D01*
X286426Y201875D01*
Y201888D01*
X286592Y202221D01*
X286773Y202512D01*
X286981Y202762D01*
X287161Y202970D01*
X287341Y203123D01*
X287480Y203234D01*
X287535Y203275D01*
X287577Y203303D01*
X287591Y203331D01*
X287605D01*
X287896Y203497D01*
X288187Y203622D01*
X288479Y203719D01*
X288742Y203774D01*
X288978Y203816D01*
X289075Y203830D01*
X289144D01*
X289214Y203844D01*
X289311D01*
X289546Y203830D01*
D02*
G37*
G36*
X301501Y194205D02*
X300225D01*
Y198463D01*
X298589D01*
X298436Y198449D01*
X298325D01*
X298228Y198435D01*
X298159Y198421D01*
X298103D01*
X298076Y198407D01*
X298062D01*
X297840Y198338D01*
X297743Y198296D01*
X297659Y198255D01*
X297576Y198213D01*
X297521Y198186D01*
X297493Y198172D01*
X297479Y198158D01*
X297368Y198074D01*
X297257Y197978D01*
X297049Y197769D01*
X296952Y197672D01*
X296883Y197589D01*
X296841Y197534D01*
X296827Y197520D01*
X296689Y197326D01*
X296536Y197118D01*
X296383Y196896D01*
X296231Y196688D01*
X296106Y196493D01*
X296009Y196341D01*
X295968Y196285D01*
X295940Y196244D01*
X295912Y196216D01*
Y196202D01*
X294650Y194205D01*
X293069D01*
X294719Y196812D01*
X294914Y197090D01*
X295094Y197339D01*
X295274Y197547D01*
X295427Y197742D01*
X295565Y197880D01*
X295676Y197991D01*
X295746Y198061D01*
X295773Y198088D01*
X295884Y198172D01*
X296009Y198269D01*
X296259Y198421D01*
X296370Y198477D01*
X296453Y198532D01*
X296508Y198560D01*
X296536Y198574D01*
X296286Y198615D01*
X296051Y198657D01*
X295843Y198726D01*
X295635Y198782D01*
X295454Y198851D01*
X295288Y198934D01*
X295135Y199004D01*
X294997Y199073D01*
X294886Y199156D01*
X294775Y199226D01*
X294692Y199281D01*
X294622Y199337D01*
X294567Y199378D01*
X294525Y199420D01*
X294511Y199434D01*
X294497Y199447D01*
X294387Y199586D01*
X294275Y199725D01*
X294109Y200016D01*
X293998Y200307D01*
X293915Y200585D01*
X293860Y200821D01*
X293846Y200918D01*
Y201015D01*
X293832Y201084D01*
Y201140D01*
Y201167D01*
Y201181D01*
X293846Y201472D01*
X293887Y201736D01*
X293957Y201985D01*
X294026Y202193D01*
X294109Y202374D01*
X294165Y202512D01*
X294220Y202596D01*
X294234Y202610D01*
Y202623D01*
X294400Y202845D01*
X294567Y203039D01*
X294747Y203206D01*
X294914Y203331D01*
X295066Y203428D01*
X295191Y203483D01*
X295274Y203525D01*
X295288Y203539D01*
X295302D01*
X295427Y203580D01*
X295579Y203622D01*
X295884Y203691D01*
X296217Y203733D01*
X296522Y203774D01*
X296813Y203788D01*
X296938D01*
X297049Y203802D01*
X301501D01*
Y194205D01*
D02*
G37*
G36*
X300489Y342576D02*
X300725Y342562D01*
X300946Y342521D01*
X301154Y342479D01*
X301348Y342424D01*
X301529Y342368D01*
X301695Y342299D01*
X301848Y342229D01*
X301987Y342160D01*
X302097Y342091D01*
X302194Y342035D01*
X302278Y341980D01*
X302347Y341938D01*
X302389Y341897D01*
X302416Y341883D01*
X302430Y341869D01*
X302569Y341730D01*
X302694Y341578D01*
X302819Y341411D01*
X302916Y341245D01*
X303082Y340912D01*
X303193Y340579D01*
X303235Y340427D01*
X303276Y340274D01*
X303304Y340149D01*
X303332Y340038D01*
X303346Y339941D01*
Y339872D01*
X303360Y339830D01*
Y339816D01*
X302153Y339692D01*
X302125Y340010D01*
X302070Y340288D01*
X301987Y340537D01*
X301889Y340732D01*
X301806Y340898D01*
X301723Y341009D01*
X301667Y341078D01*
X301640Y341106D01*
X301432Y341273D01*
X301210Y341397D01*
X300974Y341494D01*
X300766Y341550D01*
X300572Y341591D01*
X300406Y341605D01*
X300350Y341619D01*
X300267D01*
X299976Y341605D01*
X299712Y341550D01*
X299490Y341467D01*
X299296Y341384D01*
X299144Y341286D01*
X299046Y341217D01*
X298977Y341162D01*
X298949Y341134D01*
X298783Y340940D01*
X298658Y340746D01*
X298561Y340551D01*
X298505Y340357D01*
X298464Y340205D01*
X298450Y340066D01*
X298436Y339983D01*
Y339969D01*
Y339955D01*
X298464Y339705D01*
X298519Y339442D01*
X298617Y339206D01*
X298714Y338984D01*
X298825Y338804D01*
X298922Y338651D01*
X298949Y338596D01*
X298977Y338554D01*
X299005Y338540D01*
Y338527D01*
X299116Y338374D01*
X299254Y338222D01*
X299407Y338055D01*
X299573Y337889D01*
X299920Y337556D01*
X300267Y337223D01*
X300447Y337070D01*
X300600Y336932D01*
X300752Y336807D01*
X300877Y336696D01*
X300974Y336613D01*
X301057Y336543D01*
X301113Y336502D01*
X301127Y336488D01*
X301473Y336197D01*
X301792Y335919D01*
X302056Y335670D01*
X302264Y335462D01*
X302444Y335281D01*
X302569Y335157D01*
X302638Y335073D01*
X302666Y335060D01*
Y335046D01*
X302860Y334810D01*
X303013Y334588D01*
X303151Y334366D01*
X303262Y334172D01*
X303346Y334006D01*
X303401Y333881D01*
X303429Y333797D01*
X303443Y333784D01*
Y333770D01*
X303498Y333617D01*
X303526Y333479D01*
X303554Y333340D01*
X303568Y333215D01*
X303581Y333104D01*
Y333021D01*
Y332965D01*
Y332952D01*
X297216D01*
Y334089D01*
X301945D01*
X301779Y334324D01*
X301695Y334422D01*
X301626Y334519D01*
X301557Y334602D01*
X301501Y334657D01*
X301460Y334699D01*
X301446Y334713D01*
X301376Y334782D01*
X301293Y334851D01*
X301099Y335032D01*
X300877Y335240D01*
X300641Y335448D01*
X300419Y335628D01*
X300322Y335711D01*
X300239Y335795D01*
X300170Y335850D01*
X300114Y335892D01*
X300086Y335919D01*
X300073Y335933D01*
X299851Y336127D01*
X299629Y336308D01*
X299435Y336488D01*
X299254Y336641D01*
X299088Y336793D01*
X298949Y336932D01*
X298811Y337057D01*
X298700Y337168D01*
X298589Y337279D01*
X298505Y337362D01*
X298436Y337431D01*
X298367Y337500D01*
X298298Y337584D01*
X298270Y337611D01*
X298076Y337847D01*
X297909Y338055D01*
X297771Y338263D01*
X297660Y338429D01*
X297576Y338582D01*
X297521Y338693D01*
X297493Y338762D01*
X297479Y338790D01*
X297396Y338998D01*
X297341Y339206D01*
X297285Y339400D01*
X297257Y339567D01*
X297243Y339719D01*
X297230Y339830D01*
Y339900D01*
Y339927D01*
X297243Y340135D01*
X297271Y340330D01*
X297299Y340524D01*
X297354Y340690D01*
X297493Y341023D01*
X297632Y341286D01*
X297715Y341411D01*
X297784Y341508D01*
X297854Y341605D01*
X297923Y341675D01*
X297978Y341730D01*
X298006Y341786D01*
X298034Y341800D01*
X298048Y341813D01*
X298200Y341952D01*
X298367Y342077D01*
X298547Y342174D01*
X298727Y342257D01*
X299088Y342396D01*
X299449Y342493D01*
X299601Y342521D01*
X299754Y342548D01*
X299892Y342562D01*
X300003Y342576D01*
X300100Y342590D01*
X300239D01*
X300489Y342576D01*
D02*
G37*
G36*
X292417Y342354D02*
X292570Y342132D01*
X292750Y341911D01*
X292917Y341716D01*
X293083Y341550D01*
X293208Y341411D01*
X293263Y341370D01*
X293305Y341328D01*
X293319Y341314D01*
X293333Y341300D01*
X293624Y341064D01*
X293915Y340843D01*
X294193Y340648D01*
X294470Y340496D01*
X294706Y340357D01*
X294803Y340302D01*
X294886Y340260D01*
X294955Y340219D01*
X295011Y340205D01*
X295038Y340177D01*
X295052D01*
Y339040D01*
X294844Y339123D01*
X294636Y339220D01*
X294428Y339317D01*
X294234Y339414D01*
X294068Y339497D01*
X293929Y339567D01*
X293846Y339622D01*
X293832Y339636D01*
X293818D01*
X293568Y339789D01*
X293347Y339941D01*
X293152Y340080D01*
X293000Y340205D01*
X292861Y340302D01*
X292778Y340385D01*
X292708Y340440D01*
X292695Y340454D01*
Y332952D01*
X291516D01*
Y342590D01*
X292279D01*
X292417Y342354D01*
D02*
G37*
G36*
X308921Y342687D02*
X309364Y342618D01*
X309753Y342535D01*
X309933Y342479D01*
X310100Y342424D01*
X310252Y342368D01*
X310391Y342313D01*
X310502Y342271D01*
X310613Y342229D01*
X310682Y342188D01*
X310737Y342160D01*
X310779Y342146D01*
X310793Y342132D01*
X311167Y341897D01*
X311486Y341619D01*
X311764Y341342D01*
X311999Y341064D01*
X312180Y340815D01*
X312249Y340704D01*
X312305Y340607D01*
X312360Y340537D01*
X312388Y340482D01*
X312402Y340440D01*
X312416Y340427D01*
X312610Y339997D01*
X312748Y339553D01*
X312845Y339109D01*
X312915Y338707D01*
X312943Y338527D01*
X312956Y338346D01*
X312970Y338208D01*
Y338069D01*
X312984Y337972D01*
Y337889D01*
Y337833D01*
Y337819D01*
X312956Y337320D01*
X312901Y336835D01*
X312832Y336405D01*
X312776Y336197D01*
X312735Y336016D01*
X312693Y335850D01*
X312637Y335698D01*
X312596Y335559D01*
X312568Y335448D01*
X312526Y335365D01*
X312513Y335295D01*
X312485Y335254D01*
Y335240D01*
X312277Y334824D01*
X312041Y334449D01*
X311791Y334130D01*
X311667Y334006D01*
X311556Y333881D01*
X311445Y333770D01*
X311334Y333673D01*
X311237Y333590D01*
X311154Y333534D01*
X311098Y333479D01*
X311043Y333437D01*
X311015Y333423D01*
X311001Y333409D01*
X310807Y333298D01*
X310613Y333201D01*
X310197Y333049D01*
X309781Y332938D01*
X309378Y332868D01*
X309184Y332841D01*
X309018Y332813D01*
X308865Y332799D01*
X308740D01*
X308629Y332785D01*
X308477D01*
X308200Y332799D01*
X307936Y332827D01*
X307686Y332854D01*
X307451Y332910D01*
X307229Y332979D01*
X307021Y333049D01*
X306827Y333118D01*
X306646Y333201D01*
X306494Y333270D01*
X306341Y333340D01*
X306230Y333409D01*
X306119Y333479D01*
X306050Y333534D01*
X305981Y333562D01*
X305953Y333590D01*
X305939Y333603D01*
X305745Y333770D01*
X305578Y333936D01*
X305426Y334130D01*
X305273Y334324D01*
X305024Y334713D01*
X304830Y335101D01*
X304746Y335281D01*
X304677Y335448D01*
X304622Y335600D01*
X304580Y335725D01*
X304538Y335836D01*
X304510Y335919D01*
X304497Y335975D01*
Y335989D01*
X305773Y336308D01*
X305828Y336086D01*
X305897Y335878D01*
X305967Y335684D01*
X306036Y335503D01*
X306119Y335337D01*
X306203Y335198D01*
X306300Y335060D01*
X306383Y334935D01*
X306452Y334824D01*
X306535Y334741D01*
X306605Y334657D01*
X306660Y334588D01*
X306716Y334546D01*
X306757Y334505D01*
X306771Y334491D01*
X306785Y334477D01*
X306924Y334366D01*
X307076Y334283D01*
X307381Y334130D01*
X307673Y334019D01*
X307964Y333950D01*
X308213Y333895D01*
X308311Y333881D01*
X308408D01*
X308491Y333867D01*
X308588D01*
X308907Y333881D01*
X309212Y333936D01*
X309489Y334006D01*
X309739Y334089D01*
X309933Y334172D01*
X310016Y334214D01*
X310086Y334241D01*
X310141Y334269D01*
X310183Y334297D01*
X310210Y334311D01*
X310224D01*
X310488Y334505D01*
X310710Y334713D01*
X310904Y334949D01*
X311056Y335171D01*
X311181Y335365D01*
X311264Y335531D01*
X311292Y335600D01*
X311320Y335642D01*
X311334Y335670D01*
Y335684D01*
X311445Y336044D01*
X311528Y336405D01*
X311597Y336765D01*
X311639Y337098D01*
X311653Y337251D01*
X311667Y337389D01*
Y337514D01*
X311681Y337611D01*
Y337695D01*
Y337764D01*
Y337805D01*
Y337819D01*
X311667Y338180D01*
X311639Y338513D01*
X311583Y338818D01*
X311528Y339095D01*
X311486Y339331D01*
X311459Y339428D01*
X311431Y339511D01*
X311417Y339581D01*
X311403Y339622D01*
X311389Y339650D01*
Y339664D01*
X311251Y339983D01*
X311098Y340274D01*
X310932Y340510D01*
X310751Y340718D01*
X310599Y340884D01*
X310474Y340995D01*
X310377Y341064D01*
X310363Y341092D01*
X310349D01*
X310058Y341273D01*
X309739Y341411D01*
X309434Y341508D01*
X309143Y341564D01*
X308879Y341605D01*
X308768Y341619D01*
X308671D01*
X308602Y341633D01*
X308491D01*
X308144Y341619D01*
X307825Y341564D01*
X307562Y341481D01*
X307326Y341397D01*
X307146Y341300D01*
X307007Y341231D01*
X306924Y341175D01*
X306896Y341148D01*
X306674Y340940D01*
X306466Y340704D01*
X306300Y340454D01*
X306161Y340205D01*
X306050Y339983D01*
X306008Y339872D01*
X305981Y339789D01*
X305953Y339719D01*
X305925Y339664D01*
X305911Y339636D01*
Y339622D01*
X304663Y339913D01*
X304746Y340163D01*
X304830Y340385D01*
X304940Y340593D01*
X305037Y340801D01*
X305149Y340981D01*
X305273Y341148D01*
X305384Y341314D01*
X305495Y341453D01*
X305606Y341564D01*
X305703Y341675D01*
X305800Y341772D01*
X305870Y341841D01*
X305939Y341911D01*
X305994Y341952D01*
X306022Y341966D01*
X306036Y341980D01*
X306230Y342105D01*
X306424Y342229D01*
X306618Y342327D01*
X306827Y342410D01*
X307243Y342535D01*
X307617Y342618D01*
X307797Y342659D01*
X307950Y342673D01*
X308102Y342687D01*
X308227Y342701D01*
X308324Y342715D01*
X308463D01*
X308921Y342687D01*
D02*
G37*
G36*
X321842Y430332D02*
X321994Y430110D01*
X322175Y429888D01*
X322341Y429694D01*
X322508Y429527D01*
X322632Y429389D01*
X322688Y429347D01*
X322729Y429305D01*
X322743Y429292D01*
X322757Y429278D01*
X323048Y429042D01*
X323340Y428820D01*
X323617Y428626D01*
X323894Y428473D01*
X324130Y428335D01*
X324227Y428279D01*
X324310Y428238D01*
X324380Y428196D01*
X324435Y428182D01*
X324463Y428154D01*
X324477D01*
Y427017D01*
X324269Y427100D01*
X324061Y427197D01*
X323853Y427295D01*
X323659Y427392D01*
X323492Y427475D01*
X323354Y427544D01*
X323270Y427600D01*
X323256Y427614D01*
X323242D01*
X322993Y427766D01*
X322771Y427919D01*
X322577Y428057D01*
X322424Y428182D01*
X322286Y428279D01*
X322202Y428363D01*
X322133Y428418D01*
X322119Y428432D01*
Y420929D01*
X320940D01*
Y430568D01*
X321703D01*
X321842Y430332D01*
D02*
G37*
G36*
X330884Y430665D02*
X331328Y430595D01*
X331716Y430512D01*
X331896Y430457D01*
X332063Y430401D01*
X332215Y430346D01*
X332354Y430290D01*
X332465Y430249D01*
X332576Y430207D01*
X332645Y430165D01*
X332701Y430138D01*
X332742Y430124D01*
X332756Y430110D01*
X333131Y429874D01*
X333450Y429597D01*
X333727Y429319D01*
X333963Y429042D01*
X334143Y428792D01*
X334212Y428681D01*
X334268Y428584D01*
X334323Y428515D01*
X334351Y428460D01*
X334365Y428418D01*
X334379Y428404D01*
X334573Y427974D01*
X334712Y427530D01*
X334809Y427087D01*
X334878Y426684D01*
X334906Y426504D01*
X334920Y426324D01*
X334934Y426185D01*
Y426046D01*
X334947Y425949D01*
Y425866D01*
Y425811D01*
Y425797D01*
X334920Y425298D01*
X334864Y424812D01*
X334795Y424382D01*
X334739Y424174D01*
X334698Y423994D01*
X334656Y423828D01*
X334601Y423675D01*
X334559Y423536D01*
X334531Y423425D01*
X334490Y423342D01*
X334476Y423273D01*
X334448Y423231D01*
Y423217D01*
X334240Y422801D01*
X334004Y422427D01*
X333755Y422108D01*
X333630Y421983D01*
X333519Y421858D01*
X333408Y421747D01*
X333297Y421650D01*
X333200Y421567D01*
X333117Y421511D01*
X333061Y421456D01*
X333006Y421414D01*
X332978Y421401D01*
X332964Y421387D01*
X332770Y421276D01*
X332576Y421179D01*
X332160Y421026D01*
X331744Y420915D01*
X331342Y420846D01*
X331147Y420818D01*
X330981Y420790D01*
X330829Y420776D01*
X330704D01*
X330593Y420763D01*
X330440D01*
X330163Y420776D01*
X329899Y420804D01*
X329650Y420832D01*
X329414Y420887D01*
X329192Y420957D01*
X328984Y421026D01*
X328790Y421095D01*
X328610Y421179D01*
X328457Y421248D01*
X328304Y421317D01*
X328194Y421387D01*
X328083Y421456D01*
X328013Y421511D01*
X327944Y421539D01*
X327916Y421567D01*
X327902Y421581D01*
X327708Y421747D01*
X327542Y421914D01*
X327389Y422108D01*
X327237Y422302D01*
X326987Y422690D01*
X326793Y423079D01*
X326710Y423259D01*
X326640Y423425D01*
X326585Y423578D01*
X326543Y423703D01*
X326502Y423814D01*
X326474Y423897D01*
X326460Y423952D01*
Y423966D01*
X327736Y424285D01*
X327791Y424063D01*
X327861Y423855D01*
X327930Y423661D01*
X327999Y423481D01*
X328083Y423314D01*
X328166Y423176D01*
X328263Y423037D01*
X328346Y422912D01*
X328415Y422801D01*
X328499Y422718D01*
X328568Y422635D01*
X328623Y422565D01*
X328679Y422524D01*
X328721Y422482D01*
X328734Y422468D01*
X328748Y422455D01*
X328887Y422344D01*
X329039Y422260D01*
X329345Y422108D01*
X329636Y421997D01*
X329927Y421928D01*
X330177Y421872D01*
X330274Y421858D01*
X330371D01*
X330454Y421844D01*
X330551D01*
X330870Y421858D01*
X331175Y421914D01*
X331453Y421983D01*
X331702Y422066D01*
X331896Y422149D01*
X331980Y422191D01*
X332049Y422219D01*
X332104Y422247D01*
X332146Y422274D01*
X332174Y422288D01*
X332188D01*
X332451Y422482D01*
X332673Y422690D01*
X332867Y422926D01*
X333020Y423148D01*
X333144Y423342D01*
X333228Y423509D01*
X333256Y423578D01*
X333283Y423619D01*
X333297Y423647D01*
Y423661D01*
X333408Y424022D01*
X333491Y424382D01*
X333561Y424743D01*
X333602Y425076D01*
X333616Y425228D01*
X333630Y425367D01*
Y425492D01*
X333644Y425589D01*
Y425672D01*
Y425741D01*
Y425783D01*
Y425797D01*
X333630Y426157D01*
X333602Y426490D01*
X333547Y426795D01*
X333491Y427073D01*
X333450Y427309D01*
X333422Y427406D01*
X333394Y427489D01*
X333380Y427558D01*
X333366Y427600D01*
X333353Y427627D01*
Y427641D01*
X333214Y427960D01*
X333061Y428251D01*
X332895Y428487D01*
X332715Y428695D01*
X332562Y428862D01*
X332437Y428973D01*
X332340Y429042D01*
X332326Y429070D01*
X332312D01*
X332021Y429250D01*
X331702Y429389D01*
X331397Y429486D01*
X331106Y429541D01*
X330842Y429583D01*
X330731Y429597D01*
X330634D01*
X330565Y429611D01*
X330454D01*
X330107Y429597D01*
X329788Y429541D01*
X329525Y429458D01*
X329289Y429375D01*
X329109Y429278D01*
X328970Y429208D01*
X328887Y429153D01*
X328859Y429125D01*
X328637Y428917D01*
X328429Y428681D01*
X328263Y428432D01*
X328124Y428182D01*
X328013Y427960D01*
X327972Y427849D01*
X327944Y427766D01*
X327916Y427697D01*
X327888Y427641D01*
X327875Y427614D01*
Y427600D01*
X326626Y427891D01*
X326710Y428141D01*
X326793Y428363D01*
X326904Y428571D01*
X327001Y428778D01*
X327112Y428959D01*
X327237Y429125D01*
X327348Y429292D01*
X327458Y429430D01*
X327569Y429541D01*
X327667Y429652D01*
X327764Y429749D01*
X327833Y429819D01*
X327902Y429888D01*
X327958Y429930D01*
X327985Y429944D01*
X327999Y429957D01*
X328194Y430082D01*
X328388Y430207D01*
X328582Y430304D01*
X328790Y430387D01*
X329206Y430512D01*
X329580Y430595D01*
X329761Y430637D01*
X329913Y430651D01*
X330066Y430665D01*
X330191Y430678D01*
X330288Y430692D01*
X330426D01*
X330884Y430665D01*
D02*
G37*
G36*
X315019Y430554D02*
X315240Y430540D01*
X315629Y430457D01*
X315809Y430401D01*
X315975Y430346D01*
X316128Y430276D01*
X316267Y430207D01*
X316378Y430138D01*
X316489Y430068D01*
X316586Y430013D01*
X316655Y429957D01*
X316710Y429916D01*
X316752Y429874D01*
X316780Y429860D01*
X316794Y429846D01*
X316919Y429708D01*
X317043Y429569D01*
X317140Y429417D01*
X317224Y429264D01*
X317362Y428973D01*
X317446Y428695D01*
X317501Y428460D01*
X317515Y428349D01*
X317529Y428265D01*
X317543Y428182D01*
Y428127D01*
Y428099D01*
Y428085D01*
X317529Y427836D01*
X317487Y427600D01*
X317432Y427392D01*
X317362Y427211D01*
X317307Y427073D01*
X317251Y426962D01*
X317210Y426906D01*
X317196Y426879D01*
X317043Y426712D01*
X316877Y426560D01*
X316697Y426421D01*
X316516Y426310D01*
X316350Y426227D01*
X316225Y426171D01*
X316170Y426143D01*
X316128Y426130D01*
X316114Y426116D01*
X316100D01*
X316419Y426019D01*
X316683Y425894D01*
X316919Y425741D01*
X317113Y425603D01*
X317265Y425464D01*
X317376Y425353D01*
X317432Y425284D01*
X317459Y425270D01*
Y425256D01*
X317612Y425006D01*
X317737Y424743D01*
X317820Y424493D01*
X317875Y424244D01*
X317903Y424022D01*
X317917Y423925D01*
Y423841D01*
X317931Y423786D01*
Y423730D01*
Y423703D01*
Y423689D01*
X317917Y423467D01*
X317889Y423245D01*
X317848Y423037D01*
X317792Y422829D01*
X317654Y422482D01*
X317584Y422316D01*
X317501Y422177D01*
X317418Y422038D01*
X317348Y421928D01*
X317265Y421830D01*
X317210Y421747D01*
X317154Y421678D01*
X317113Y421636D01*
X317085Y421609D01*
X317071Y421595D01*
X316905Y421442D01*
X316724Y421317D01*
X316530Y421206D01*
X316336Y421109D01*
X316156Y421040D01*
X315962Y420971D01*
X315587Y420874D01*
X315421Y420832D01*
X315268Y420804D01*
X315130Y420790D01*
X315005Y420776D01*
X314908Y420763D01*
X314769D01*
X314505Y420776D01*
X314270Y420804D01*
X314034Y420846D01*
X313812Y420887D01*
X313618Y420957D01*
X313424Y421026D01*
X313243Y421095D01*
X313091Y421179D01*
X312952Y421262D01*
X312827Y421331D01*
X312730Y421401D01*
X312633Y421470D01*
X312564Y421511D01*
X312522Y421553D01*
X312495Y421581D01*
X312481Y421595D01*
X312328Y421761D01*
X312189Y421928D01*
X312078Y422094D01*
X311981Y422274D01*
X311884Y422441D01*
X311815Y422621D01*
X311718Y422940D01*
X311676Y423092D01*
X311649Y423231D01*
X311635Y423356D01*
X311621Y423453D01*
X311607Y423536D01*
Y423606D01*
Y423647D01*
Y423661D01*
X311621Y423980D01*
X311676Y424271D01*
X311759Y424535D01*
X311843Y424757D01*
X311926Y424937D01*
X312009Y425076D01*
X312065Y425159D01*
X312078Y425173D01*
Y425187D01*
X312273Y425409D01*
X312481Y425603D01*
X312703Y425755D01*
X312911Y425894D01*
X313105Y425991D01*
X313271Y426060D01*
X313327Y426088D01*
X313368Y426102D01*
X313396Y426116D01*
X313410D01*
X313160Y426227D01*
X312952Y426352D01*
X312772Y426476D01*
X312619Y426601D01*
X312508Y426712D01*
X312425Y426795D01*
X312370Y426851D01*
X312356Y426879D01*
X312231Y427073D01*
X312148Y427267D01*
X312078Y427461D01*
X312037Y427655D01*
X312009Y427808D01*
X311995Y427933D01*
Y428016D01*
Y428030D01*
Y428044D01*
X312009Y428238D01*
X312023Y428418D01*
X312120Y428765D01*
X312245Y429070D01*
X312384Y429333D01*
X312522Y429541D01*
X312592Y429624D01*
X312647Y429708D01*
X312703Y429763D01*
X312744Y429805D01*
X312758Y429819D01*
X312772Y429832D01*
X312924Y429957D01*
X313077Y430082D01*
X313243Y430179D01*
X313410Y430262D01*
X313743Y430387D01*
X314076Y430471D01*
X314214Y430512D01*
X314353Y430526D01*
X314478Y430540D01*
X314589Y430554D01*
X314672Y430568D01*
X314797D01*
X315019Y430554D01*
D02*
G37*
G36*
X197515Y163761D02*
X197751Y163747D01*
X197973Y163705D01*
X198181Y163663D01*
X198375Y163608D01*
X198555Y163552D01*
X198722Y163483D01*
X198874Y163414D01*
X199013Y163344D01*
X199124Y163275D01*
X199221Y163220D01*
X199304Y163164D01*
X199373Y163123D01*
X199415Y163081D01*
X199443Y163067D01*
X199457Y163053D01*
X199595Y162915D01*
X199720Y162762D01*
X199845Y162596D01*
X199942Y162429D01*
X200109Y162096D01*
X200219Y161763D01*
X200261Y161611D01*
X200303Y161458D01*
X200330Y161334D01*
X200358Y161223D01*
X200372Y161126D01*
Y161056D01*
X200386Y161014D01*
Y161001D01*
X199179Y160876D01*
X199152Y161195D01*
X199096Y161472D01*
X199013Y161722D01*
X198916Y161916D01*
X198833Y162082D01*
X198749Y162193D01*
X198694Y162263D01*
X198666Y162290D01*
X198458Y162457D01*
X198236Y162582D01*
X198001Y162679D01*
X197792Y162734D01*
X197598Y162776D01*
X197432Y162790D01*
X197376Y162804D01*
X197293D01*
X197002Y162790D01*
X196738Y162734D01*
X196517Y162651D01*
X196322Y162568D01*
X196170Y162471D01*
X196073Y162401D01*
X196003Y162346D01*
X195976Y162318D01*
X195809Y162124D01*
X195685Y161930D01*
X195587Y161736D01*
X195532Y161542D01*
X195490Y161389D01*
X195476Y161250D01*
X195463Y161167D01*
Y161153D01*
Y161139D01*
X195490Y160890D01*
X195546Y160626D01*
X195643Y160390D01*
X195740Y160169D01*
X195851Y159988D01*
X195948Y159836D01*
X195976Y159780D01*
X196003Y159739D01*
X196031Y159725D01*
Y159711D01*
X196142Y159558D01*
X196281Y159406D01*
X196433Y159239D01*
X196600Y159073D01*
X196947Y158740D01*
X197293Y158407D01*
X197474Y158255D01*
X197626Y158116D01*
X197779Y157991D01*
X197903Y157880D01*
X198001Y157797D01*
X198084Y157728D01*
X198139Y157686D01*
X198153Y157672D01*
X198500Y157381D01*
X198819Y157104D01*
X199082Y156854D01*
X199290Y156646D01*
X199471Y156466D01*
X199595Y156341D01*
X199665Y156258D01*
X199692Y156244D01*
Y156230D01*
X199887Y155994D01*
X200039Y155772D01*
X200178Y155550D01*
X200289Y155356D01*
X200372Y155190D01*
X200427Y155065D01*
X200455Y154982D01*
X200469Y154968D01*
Y154954D01*
X200525Y154802D01*
X200552Y154663D01*
X200580Y154524D01*
X200594Y154399D01*
X200608Y154288D01*
Y154205D01*
Y154150D01*
Y154136D01*
X194242D01*
Y155273D01*
X198971D01*
X198805Y155509D01*
X198722Y155606D01*
X198652Y155703D01*
X198583Y155786D01*
X198528Y155842D01*
X198486Y155883D01*
X198472Y155897D01*
X198403Y155966D01*
X198319Y156036D01*
X198125Y156216D01*
X197903Y156424D01*
X197668Y156632D01*
X197446Y156812D01*
X197349Y156896D01*
X197265Y156979D01*
X197196Y157034D01*
X197141Y157076D01*
X197113Y157104D01*
X197099Y157118D01*
X196877Y157312D01*
X196655Y157492D01*
X196461Y157672D01*
X196281Y157825D01*
X196114Y157977D01*
X195976Y158116D01*
X195837Y158241D01*
X195726Y158352D01*
X195615Y158463D01*
X195532Y158546D01*
X195463Y158615D01*
X195393Y158685D01*
X195324Y158768D01*
X195296Y158796D01*
X195102Y159031D01*
X194936Y159239D01*
X194797Y159447D01*
X194686Y159614D01*
X194603Y159766D01*
X194547Y159877D01*
X194520Y159947D01*
X194506Y159974D01*
X194422Y160182D01*
X194367Y160390D01*
X194312Y160585D01*
X194284Y160751D01*
X194270Y160904D01*
X194256Y161014D01*
Y161084D01*
Y161112D01*
X194270Y161320D01*
X194298Y161514D01*
X194325Y161708D01*
X194381Y161874D01*
X194520Y162207D01*
X194658Y162471D01*
X194741Y162596D01*
X194811Y162693D01*
X194880Y162790D01*
X194949Y162859D01*
X195005Y162915D01*
X195033Y162970D01*
X195060Y162984D01*
X195074Y162998D01*
X195227Y163136D01*
X195393Y163261D01*
X195574Y163358D01*
X195754Y163442D01*
X196114Y163580D01*
X196475Y163677D01*
X196628Y163705D01*
X196780Y163733D01*
X196919Y163747D01*
X197030Y163761D01*
X197127Y163774D01*
X197265D01*
X197515Y163761D01*
D02*
G37*
G36*
X215558Y154136D02*
X214282D01*
Y158490D01*
X209775D01*
Y159628D01*
X214282D01*
Y162596D01*
X209067D01*
Y163733D01*
X215558D01*
Y154136D01*
D02*
G37*
G36*
X207473D02*
X201468D01*
Y155273D01*
X206197D01*
Y163733D01*
X207473D01*
Y154136D01*
D02*
G37*
G36*
X225819Y359015D02*
X225583Y358876D01*
X225362Y358723D01*
X225140Y358543D01*
X224946Y358377D01*
X224779Y358210D01*
X224640Y358085D01*
X224599Y358030D01*
X224557Y357988D01*
X224543Y357974D01*
X224529Y357961D01*
X224294Y357669D01*
X224072Y357378D01*
X223878Y357101D01*
X223725Y356823D01*
X223586Y356587D01*
X223531Y356490D01*
X223489Y356407D01*
X223448Y356338D01*
X223434Y356282D01*
X223406Y356255D01*
Y356241D01*
X222269D01*
X222352Y356449D01*
X222449Y356657D01*
X222546Y356865D01*
X222643Y357059D01*
X222727Y357225D01*
X222796Y357364D01*
X222851Y357447D01*
X222865Y357461D01*
Y357475D01*
X223018Y357725D01*
X223170Y357947D01*
X223309Y358141D01*
X223434Y358293D01*
X223531Y358432D01*
X223614Y358515D01*
X223670Y358585D01*
X223683Y358598D01*
X216181D01*
Y359777D01*
X225819D01*
Y359015D01*
D02*
G37*
G36*
X217318Y349584D02*
X225778D01*
Y348308D01*
X216181D01*
Y354313D01*
X217318D01*
Y349584D01*
D02*
G37*
G36*
X225778Y340223D02*
X216181D01*
Y341499D01*
X220535D01*
Y346006D01*
X221673D01*
Y341499D01*
X224640D01*
Y346713D01*
X225778D01*
Y340223D01*
D02*
G37*
G36*
X149718Y197084D02*
Y196807D01*
X149704Y196543D01*
X149690Y196294D01*
X149662Y196058D01*
X149635Y195850D01*
X149607Y195656D01*
X149565Y195476D01*
X149537Y195309D01*
X149510Y195157D01*
X149468Y195032D01*
X149440Y194921D01*
X149413Y194838D01*
X149385Y194768D01*
X149371Y194713D01*
X149357Y194685D01*
Y194671D01*
X149205Y194366D01*
X149010Y194089D01*
X148816Y193867D01*
X148608Y193673D01*
X148428Y193520D01*
X148275Y193409D01*
X148220Y193382D01*
X148178Y193354D01*
X148151Y193326D01*
X148137D01*
X147790Y193173D01*
X147430Y193062D01*
X147055Y192979D01*
X146708Y192924D01*
X146556Y192910D01*
X146403Y192896D01*
X146264Y192882D01*
X146154D01*
X146056Y192868D01*
X145932D01*
X145432Y192896D01*
X145211Y192924D01*
X145002Y192952D01*
X144795Y192993D01*
X144614Y193035D01*
X144448Y193076D01*
X144295Y193132D01*
X144157Y193187D01*
X144046Y193229D01*
X143935Y193270D01*
X143851Y193312D01*
X143782Y193354D01*
X143741Y193368D01*
X143713Y193395D01*
X143699D01*
X143394Y193603D01*
X143144Y193839D01*
X142950Y194061D01*
X142784Y194283D01*
X142659Y194477D01*
X142576Y194630D01*
X142548Y194685D01*
X142520Y194727D01*
X142506Y194754D01*
Y194768D01*
X142451Y194935D01*
X142395Y195115D01*
X142312Y195489D01*
X142257Y195878D01*
X142215Y196252D01*
X142201Y196419D01*
X142187Y196585D01*
Y196724D01*
X142173Y196849D01*
Y196946D01*
Y197015D01*
Y197070D01*
Y197084D01*
Y202632D01*
X143449D01*
Y197084D01*
Y196765D01*
X143477Y196460D01*
X143505Y196197D01*
X143546Y195947D01*
X143588Y195725D01*
X143643Y195517D01*
X143685Y195337D01*
X143741Y195184D01*
X143796Y195060D01*
X143851Y194935D01*
X143907Y194851D01*
X143948Y194768D01*
X143990Y194713D01*
X144018Y194671D01*
X144032Y194657D01*
X144046Y194643D01*
X144170Y194533D01*
X144309Y194436D01*
X144614Y194283D01*
X144933Y194172D01*
X145266Y194103D01*
X145571Y194047D01*
X145696Y194033D01*
X145821D01*
X145904Y194019D01*
X146043D01*
X146334Y194033D01*
X146597Y194075D01*
X146847Y194116D01*
X147041Y194186D01*
X147208Y194241D01*
X147332Y194283D01*
X147402Y194324D01*
X147430Y194338D01*
X147624Y194463D01*
X147790Y194616D01*
X147929Y194768D01*
X148026Y194907D01*
X148109Y195046D01*
X148178Y195143D01*
X148206Y195212D01*
X148220Y195240D01*
X148262Y195365D01*
X148289Y195489D01*
X148345Y195781D01*
X148386Y196086D01*
X148414Y196391D01*
X148428Y196654D01*
Y196779D01*
X148442Y196876D01*
Y196959D01*
Y197029D01*
Y197070D01*
Y197084D01*
Y202632D01*
X149718D01*
Y197084D01*
D02*
G37*
G36*
X140939Y196419D02*
Y195337D01*
X136765D01*
Y193035D01*
X135586D01*
Y195337D01*
X134282D01*
Y196419D01*
X135586D01*
Y202632D01*
X136543D01*
X140939Y196419D01*
D02*
G37*
G36*
X140950Y332042D02*
X141325Y331972D01*
X141644Y331861D01*
X141921Y331750D01*
X142046Y331681D01*
X142143Y331626D01*
X142240Y331570D01*
X142310Y331515D01*
X142365Y331473D01*
X142407Y331445D01*
X142434Y331431D01*
X142448Y331418D01*
X142712Y331154D01*
X142920Y330863D01*
X143086Y330558D01*
X143225Y330253D01*
X143308Y329989D01*
X143350Y329878D01*
X143377Y329781D01*
X143391Y329698D01*
X143405Y329642D01*
X143419Y329601D01*
Y329587D01*
X142240Y329379D01*
X142185Y329684D01*
X142101Y329948D01*
X142004Y330169D01*
X141907Y330350D01*
X141810Y330488D01*
X141727Y330585D01*
X141672Y330655D01*
X141658Y330669D01*
X141477Y330807D01*
X141283Y330918D01*
X141103Y330988D01*
X140923Y331043D01*
X140756Y331071D01*
X140631Y331099D01*
X140520D01*
X140271Y331085D01*
X140049Y331029D01*
X139855Y330960D01*
X139688Y330891D01*
X139564Y330807D01*
X139466Y330738D01*
X139397Y330682D01*
X139383Y330669D01*
X139231Y330502D01*
X139120Y330322D01*
X139050Y330142D01*
X138995Y329975D01*
X138967Y329823D01*
X138940Y329712D01*
Y329628D01*
Y329615D01*
Y329601D01*
Y329448D01*
X138967Y329310D01*
X139037Y329074D01*
X139134Y328866D01*
X139245Y328685D01*
X139356Y328561D01*
X139453Y328464D01*
X139522Y328408D01*
X139536Y328394D01*
X139550D01*
X139785Y328269D01*
X140007Y328172D01*
X140243Y328103D01*
X140451Y328061D01*
X140631Y328034D01*
X140784Y328006D01*
X140964D01*
X141020Y328020D01*
X141089D01*
X141228Y326980D01*
X141047Y327021D01*
X140881Y327049D01*
X140742Y327077D01*
X140618Y327091D01*
X140520Y327104D01*
X140396D01*
X140104Y327077D01*
X139841Y327021D01*
X139605Y326938D01*
X139411Y326841D01*
X139258Y326744D01*
X139148Y326661D01*
X139078Y326605D01*
X139050Y326577D01*
X138870Y326369D01*
X138731Y326147D01*
X138634Y325926D01*
X138579Y325704D01*
X138537Y325523D01*
X138523Y325371D01*
X138510Y325315D01*
Y325274D01*
Y325246D01*
Y325232D01*
X138537Y324927D01*
X138607Y324650D01*
X138690Y324414D01*
X138801Y324206D01*
X138912Y324039D01*
X138995Y323915D01*
X139064Y323831D01*
X139092Y323804D01*
X139314Y323610D01*
X139550Y323471D01*
X139785Y323374D01*
X140007Y323304D01*
X140202Y323263D01*
X140354Y323249D01*
X140409Y323235D01*
X140493D01*
X140742Y323249D01*
X140978Y323304D01*
X141186Y323374D01*
X141353Y323457D01*
X141491Y323526D01*
X141602Y323596D01*
X141658Y323651D01*
X141685Y323665D01*
X141852Y323859D01*
X141990Y324081D01*
X142115Y324317D01*
X142212Y324566D01*
X142282Y324775D01*
X142310Y324872D01*
X142323Y324955D01*
X142337Y325024D01*
X142351Y325080D01*
X142365Y325107D01*
Y325121D01*
X143544Y324969D01*
X143516Y324747D01*
X143475Y324539D01*
X143350Y324151D01*
X143197Y323818D01*
X143114Y323679D01*
X143031Y323540D01*
X142948Y323415D01*
X142864Y323318D01*
X142795Y323221D01*
X142726Y323152D01*
X142684Y323097D01*
X142642Y323055D01*
X142615Y323027D01*
X142601Y323013D01*
X142434Y322888D01*
X142268Y322764D01*
X142101Y322667D01*
X141921Y322583D01*
X141574Y322445D01*
X141242Y322361D01*
X141089Y322334D01*
X140950Y322306D01*
X140826Y322292D01*
X140715Y322278D01*
X140631Y322264D01*
X140507D01*
X140243Y322278D01*
X140007Y322306D01*
X139772Y322348D01*
X139550Y322403D01*
X139342Y322472D01*
X139161Y322542D01*
X138981Y322625D01*
X138829Y322708D01*
X138676Y322777D01*
X138551Y322861D01*
X138440Y322930D01*
X138357Y322999D01*
X138288Y323055D01*
X138232Y323097D01*
X138204Y323124D01*
X138191Y323138D01*
X138024Y323304D01*
X137886Y323485D01*
X137761Y323665D01*
X137650Y323845D01*
X137566Y324012D01*
X137483Y324192D01*
X137372Y324525D01*
X137345Y324678D01*
X137317Y324816D01*
X137289Y324941D01*
X137275Y325052D01*
X137261Y325135D01*
Y325205D01*
Y325246D01*
Y325260D01*
X137275Y325593D01*
X137331Y325898D01*
X137414Y326161D01*
X137497Y326383D01*
X137580Y326564D01*
X137664Y326702D01*
X137719Y326786D01*
X137733Y326813D01*
X137927Y327021D01*
X138135Y327201D01*
X138357Y327340D01*
X138579Y327451D01*
X138773Y327534D01*
X138926Y327590D01*
X138981Y327604D01*
X139023Y327618D01*
X139050Y327631D01*
X139064D01*
X138829Y327756D01*
X138634Y327881D01*
X138468Y328020D01*
X138329Y328145D01*
X138218Y328256D01*
X138135Y328353D01*
X138094Y328408D01*
X138080Y328436D01*
X137969Y328630D01*
X137886Y328824D01*
X137816Y329018D01*
X137775Y329199D01*
X137747Y329351D01*
X137733Y329462D01*
Y329545D01*
Y329573D01*
X137747Y329809D01*
X137788Y330045D01*
X137844Y330253D01*
X137913Y330433D01*
X137983Y330585D01*
X138038Y330710D01*
X138080Y330780D01*
X138094Y330807D01*
X138232Y331015D01*
X138399Y331196D01*
X138565Y331348D01*
X138731Y331487D01*
X138870Y331584D01*
X138995Y331667D01*
X139078Y331709D01*
X139092Y331723D01*
X139106D01*
X139356Y331834D01*
X139605Y331917D01*
X139855Y331986D01*
X140077Y332028D01*
X140257Y332056D01*
X140409Y332069D01*
X140756D01*
X140950Y332042D01*
D02*
G37*
G36*
X152739Y326480D02*
Y326203D01*
X152725Y325939D01*
X152711Y325690D01*
X152683Y325454D01*
X152655Y325246D01*
X152628Y325052D01*
X152586Y324872D01*
X152558Y324705D01*
X152530Y324553D01*
X152489Y324428D01*
X152461Y324317D01*
X152434Y324234D01*
X152406Y324164D01*
X152392Y324109D01*
X152378Y324081D01*
Y324067D01*
X152225Y323762D01*
X152031Y323485D01*
X151837Y323263D01*
X151629Y323069D01*
X151449Y322916D01*
X151296Y322805D01*
X151241Y322777D01*
X151199Y322750D01*
X151171Y322722D01*
X151158D01*
X150811Y322570D01*
X150450Y322458D01*
X150076Y322375D01*
X149729Y322320D01*
X149577Y322306D01*
X149424Y322292D01*
X149285Y322278D01*
X149174D01*
X149077Y322264D01*
X148953D01*
X148453Y322292D01*
X148231Y322320D01*
X148023Y322348D01*
X147815Y322389D01*
X147635Y322431D01*
X147469Y322472D01*
X147316Y322528D01*
X147177Y322583D01*
X147066Y322625D01*
X146955Y322667D01*
X146872Y322708D01*
X146803Y322750D01*
X146761Y322764D01*
X146734Y322791D01*
X146720D01*
X146415Y322999D01*
X146165Y323235D01*
X145971Y323457D01*
X145804Y323679D01*
X145680Y323873D01*
X145596Y324026D01*
X145569Y324081D01*
X145541Y324123D01*
X145527Y324151D01*
Y324164D01*
X145471Y324331D01*
X145416Y324511D01*
X145333Y324885D01*
X145277Y325274D01*
X145236Y325648D01*
X145222Y325815D01*
X145208Y325981D01*
Y326120D01*
X145194Y326245D01*
Y326342D01*
Y326411D01*
Y326466D01*
Y326480D01*
Y332028D01*
X146470D01*
Y326480D01*
Y326161D01*
X146498Y325856D01*
X146525Y325593D01*
X146567Y325343D01*
X146609Y325121D01*
X146664Y324913D01*
X146706Y324733D01*
X146761Y324580D01*
X146817Y324456D01*
X146872Y324331D01*
X146928Y324248D01*
X146969Y324164D01*
X147011Y324109D01*
X147039Y324067D01*
X147052Y324053D01*
X147066Y324039D01*
X147191Y323929D01*
X147330Y323831D01*
X147635Y323679D01*
X147954Y323568D01*
X148287Y323499D01*
X148592Y323443D01*
X148717Y323429D01*
X148841D01*
X148925Y323415D01*
X149063D01*
X149355Y323429D01*
X149618Y323471D01*
X149868Y323512D01*
X150062Y323582D01*
X150228Y323637D01*
X150353Y323679D01*
X150422Y323721D01*
X150450Y323734D01*
X150644Y323859D01*
X150811Y324012D01*
X150949Y324164D01*
X151047Y324303D01*
X151130Y324442D01*
X151199Y324539D01*
X151227Y324608D01*
X151241Y324636D01*
X151282Y324761D01*
X151310Y324885D01*
X151366Y325177D01*
X151407Y325482D01*
X151435Y325787D01*
X151449Y326050D01*
Y326175D01*
X151463Y326272D01*
Y326356D01*
Y326425D01*
Y326466D01*
Y326480D01*
Y332028D01*
X152739D01*
Y326480D01*
D02*
G37*
G36*
X95470Y238957D02*
X94360Y238804D01*
X94263Y238957D01*
X94138Y239081D01*
X94027Y239206D01*
X93917Y239303D01*
X93806Y239373D01*
X93722Y239442D01*
X93667Y239470D01*
X93653Y239484D01*
X93473Y239567D01*
X93292Y239636D01*
X93126Y239678D01*
X92960Y239719D01*
X92821Y239733D01*
X92710Y239747D01*
X92446D01*
X92280Y239719D01*
X91989Y239650D01*
X91739Y239553D01*
X91517Y239456D01*
X91351Y239345D01*
X91226Y239248D01*
X91157Y239179D01*
X91129Y239165D01*
Y239151D01*
X90935Y238915D01*
X90796Y238665D01*
X90699Y238402D01*
X90630Y238138D01*
X90588Y237917D01*
X90574Y237819D01*
Y237736D01*
X90560Y237667D01*
Y237611D01*
Y237584D01*
Y237570D01*
Y237376D01*
X90588Y237195D01*
X90657Y236849D01*
X90754Y236557D01*
X90852Y236322D01*
X90962Y236127D01*
X91060Y235975D01*
X91101Y235933D01*
X91129Y235892D01*
X91143Y235878D01*
X91157Y235864D01*
X91268Y235753D01*
X91379Y235656D01*
X91628Y235490D01*
X91864Y235379D01*
X92100Y235309D01*
X92294Y235254D01*
X92460Y235240D01*
X92516Y235226D01*
X92599D01*
X92863Y235240D01*
X93098Y235295D01*
X93306Y235365D01*
X93473Y235448D01*
X93625Y235531D01*
X93736Y235600D01*
X93792Y235656D01*
X93819Y235670D01*
X93986Y235864D01*
X94124Y236072D01*
X94235Y236308D01*
X94319Y236516D01*
X94374Y236724D01*
X94416Y236876D01*
X94430Y236946D01*
X94444Y236987D01*
Y237015D01*
Y237029D01*
X95678Y236932D01*
X95650Y236710D01*
X95608Y236502D01*
X95484Y236114D01*
X95331Y235781D01*
X95248Y235628D01*
X95165Y235503D01*
X95095Y235379D01*
X95012Y235268D01*
X94943Y235184D01*
X94873Y235115D01*
X94818Y235060D01*
X94790Y235004D01*
X94762Y234990D01*
X94749Y234976D01*
X94582Y234852D01*
X94416Y234741D01*
X94235Y234644D01*
X94055Y234560D01*
X93708Y234436D01*
X93362Y234352D01*
X93209Y234311D01*
X93057Y234297D01*
X92932Y234283D01*
X92821Y234269D01*
X92724Y234255D01*
X92599D01*
X92308Y234269D01*
X92030Y234311D01*
X91767Y234366D01*
X91531Y234436D01*
X91309Y234533D01*
X91101Y234630D01*
X90907Y234727D01*
X90741Y234838D01*
X90588Y234949D01*
X90449Y235046D01*
X90338Y235157D01*
X90241Y235240D01*
X90172Y235309D01*
X90117Y235365D01*
X90089Y235406D01*
X90075Y235420D01*
X89936Y235600D01*
X89825Y235795D01*
X89714Y235975D01*
X89631Y236169D01*
X89493Y236544D01*
X89409Y236904D01*
X89382Y237057D01*
X89354Y237209D01*
X89340Y237334D01*
X89326Y237445D01*
X89312Y237542D01*
Y237611D01*
Y237653D01*
Y237667D01*
X89326Y237917D01*
X89354Y238152D01*
X89395Y238388D01*
X89451Y238596D01*
X89520Y238790D01*
X89590Y238984D01*
X89673Y239151D01*
X89742Y239303D01*
X89825Y239442D01*
X89909Y239567D01*
X89978Y239664D01*
X90047Y239761D01*
X90103Y239830D01*
X90144Y239872D01*
X90172Y239900D01*
X90186Y239914D01*
X90352Y240066D01*
X90519Y240205D01*
X90699Y240316D01*
X90879Y240413D01*
X91060Y240510D01*
X91240Y240579D01*
X91573Y240676D01*
X91725Y240718D01*
X91864Y240746D01*
X91989Y240760D01*
X92100Y240773D01*
X92183Y240787D01*
X92488D01*
X92654Y240760D01*
X92987Y240690D01*
X93292Y240593D01*
X93570Y240482D01*
X93792Y240371D01*
X93889Y240316D01*
X93972Y240274D01*
X94041Y240233D01*
X94083Y240205D01*
X94111Y240191D01*
X94124Y240177D01*
X93611Y242771D01*
X89770D01*
Y243894D01*
X94541D01*
X95470Y238957D01*
D02*
G37*
G36*
X104859Y234422D02*
X103583D01*
Y238679D01*
X101946D01*
X101794Y238665D01*
X101683D01*
X101586Y238652D01*
X101516Y238638D01*
X101461D01*
X101433Y238624D01*
X101419D01*
X101197Y238554D01*
X101100Y238513D01*
X101017Y238471D01*
X100934Y238430D01*
X100878Y238402D01*
X100851Y238388D01*
X100837Y238374D01*
X100726Y238291D01*
X100615Y238194D01*
X100407Y237986D01*
X100310Y237889D01*
X100240Y237806D01*
X100199Y237750D01*
X100185Y237736D01*
X100046Y237542D01*
X99894Y237334D01*
X99741Y237112D01*
X99589Y236904D01*
X99464Y236710D01*
X99367Y236557D01*
X99325Y236502D01*
X99297Y236460D01*
X99270Y236433D01*
Y236419D01*
X98008Y234422D01*
X96427D01*
X98077Y237029D01*
X98271Y237306D01*
X98451Y237556D01*
X98632Y237764D01*
X98784Y237958D01*
X98923Y238097D01*
X99034Y238208D01*
X99103Y238277D01*
X99131Y238305D01*
X99242Y238388D01*
X99367Y238485D01*
X99616Y238638D01*
X99727Y238693D01*
X99810Y238749D01*
X99866Y238776D01*
X99894Y238790D01*
X99644Y238832D01*
X99408Y238873D01*
X99200Y238943D01*
X98992Y238998D01*
X98812Y239068D01*
X98646Y239151D01*
X98493Y239220D01*
X98354Y239289D01*
X98243Y239373D01*
X98132Y239442D01*
X98049Y239498D01*
X97980Y239553D01*
X97924Y239595D01*
X97883Y239636D01*
X97869Y239650D01*
X97855Y239664D01*
X97744Y239803D01*
X97633Y239941D01*
X97467Y240233D01*
X97356Y240524D01*
X97273Y240801D01*
X97217Y241037D01*
X97203Y241134D01*
Y241231D01*
X97189Y241300D01*
Y241356D01*
Y241384D01*
Y241397D01*
X97203Y241689D01*
X97245Y241952D01*
X97314Y242202D01*
X97384Y242410D01*
X97467Y242590D01*
X97522Y242729D01*
X97578Y242812D01*
X97592Y242826D01*
Y242840D01*
X97758Y243062D01*
X97924Y243256D01*
X98105Y243422D01*
X98271Y243547D01*
X98424Y243644D01*
X98548Y243700D01*
X98632Y243741D01*
X98646Y243755D01*
X98659D01*
X98784Y243797D01*
X98937Y243838D01*
X99242Y243908D01*
X99575Y243949D01*
X99880Y243991D01*
X100171Y244005D01*
X100296D01*
X100407Y244019D01*
X104859D01*
Y234422D01*
D02*
G37*
G36*
X154597Y171454D02*
X154749Y171232D01*
X154930Y171010D01*
X155096Y170816D01*
X155262Y170650D01*
X155387Y170511D01*
X155443Y170470D01*
X155484Y170428D01*
X155498Y170414D01*
X155512Y170400D01*
X155803Y170165D01*
X156095Y169943D01*
X156372Y169748D01*
X156649Y169596D01*
X156885Y169457D01*
X156982Y169402D01*
X157065Y169360D01*
X157135Y169319D01*
X157190Y169305D01*
X157218Y169277D01*
X157232D01*
Y168140D01*
X157024Y168223D01*
X156816Y168320D01*
X156608Y168417D01*
X156413Y168514D01*
X156247Y168597D01*
X156108Y168667D01*
X156025Y168722D01*
X156011Y168736D01*
X155997D01*
X155748Y168889D01*
X155526Y169041D01*
X155332Y169180D01*
X155179Y169305D01*
X155041Y169402D01*
X154957Y169485D01*
X154888Y169541D01*
X154874Y169554D01*
Y162052D01*
X153695D01*
Y171690D01*
X154458D01*
X154597Y171454D01*
D02*
G37*
G36*
X163639Y171787D02*
X164083Y171718D01*
X164471Y171635D01*
X164651Y171579D01*
X164818Y171524D01*
X164970Y171468D01*
X165109Y171413D01*
X165220Y171371D01*
X165331Y171329D01*
X165400Y171288D01*
X165456Y171260D01*
X165497Y171246D01*
X165511Y171232D01*
X165886Y170997D01*
X166205Y170719D01*
X166482Y170442D01*
X166718Y170165D01*
X166898Y169915D01*
X166967Y169804D01*
X167023Y169707D01*
X167078Y169638D01*
X167106Y169582D01*
X167120Y169541D01*
X167134Y169527D01*
X167328Y169097D01*
X167467Y168653D01*
X167564Y168209D01*
X167633Y167807D01*
X167661Y167627D01*
X167675Y167446D01*
X167689Y167308D01*
Y167169D01*
X167702Y167072D01*
Y166989D01*
Y166933D01*
Y166919D01*
X167675Y166420D01*
X167619Y165935D01*
X167550Y165505D01*
X167494Y165297D01*
X167453Y165117D01*
X167411Y164950D01*
X167356Y164797D01*
X167314Y164659D01*
X167286Y164548D01*
X167245Y164465D01*
X167231Y164395D01*
X167203Y164354D01*
Y164340D01*
X166995Y163924D01*
X166759Y163549D01*
X166510Y163230D01*
X166385Y163106D01*
X166274Y162981D01*
X166163Y162870D01*
X166052Y162773D01*
X165955Y162689D01*
X165872Y162634D01*
X165816Y162579D01*
X165761Y162537D01*
X165733Y162523D01*
X165719Y162509D01*
X165525Y162398D01*
X165331Y162301D01*
X164915Y162149D01*
X164499Y162038D01*
X164097Y161968D01*
X163902Y161941D01*
X163736Y161913D01*
X163584Y161899D01*
X163459D01*
X163348Y161885D01*
X163195D01*
X162918Y161899D01*
X162654Y161927D01*
X162405Y161954D01*
X162169Y162010D01*
X161947Y162079D01*
X161739Y162149D01*
X161545Y162218D01*
X161364Y162301D01*
X161212Y162370D01*
X161059Y162440D01*
X160949Y162509D01*
X160837Y162579D01*
X160768Y162634D01*
X160699Y162662D01*
X160671Y162689D01*
X160657Y162703D01*
X160463Y162870D01*
X160297Y163036D01*
X160144Y163230D01*
X159992Y163424D01*
X159742Y163813D01*
X159548Y164201D01*
X159465Y164381D01*
X159395Y164548D01*
X159340Y164700D01*
X159298Y164825D01*
X159256Y164936D01*
X159229Y165019D01*
X159215Y165075D01*
Y165089D01*
X160491Y165408D01*
X160546Y165186D01*
X160616Y164978D01*
X160685Y164784D01*
X160754Y164603D01*
X160837Y164437D01*
X160921Y164298D01*
X161018Y164160D01*
X161101Y164035D01*
X161170Y163924D01*
X161254Y163841D01*
X161323Y163757D01*
X161378Y163688D01*
X161434Y163646D01*
X161476Y163605D01*
X161489Y163591D01*
X161503Y163577D01*
X161642Y163466D01*
X161794Y163383D01*
X162099Y163230D01*
X162391Y163119D01*
X162682Y163050D01*
X162932Y162995D01*
X163029Y162981D01*
X163126D01*
X163209Y162967D01*
X163306D01*
X163625Y162981D01*
X163930Y163036D01*
X164207Y163106D01*
X164457Y163189D01*
X164651Y163272D01*
X164734Y163314D01*
X164804Y163341D01*
X164859Y163369D01*
X164901Y163397D01*
X164929Y163411D01*
X164943D01*
X165206Y163605D01*
X165428Y163813D01*
X165622Y164049D01*
X165775Y164270D01*
X165900Y164465D01*
X165983Y164631D01*
X166010Y164700D01*
X166038Y164742D01*
X166052Y164770D01*
Y164784D01*
X166163Y165144D01*
X166246Y165505D01*
X166315Y165865D01*
X166357Y166198D01*
X166371Y166351D01*
X166385Y166489D01*
Y166614D01*
X166399Y166711D01*
Y166794D01*
Y166864D01*
Y166905D01*
Y166919D01*
X166385Y167280D01*
X166357Y167613D01*
X166302Y167918D01*
X166246Y168195D01*
X166205Y168431D01*
X166177Y168528D01*
X166149Y168611D01*
X166135Y168681D01*
X166121Y168722D01*
X166108Y168750D01*
Y168764D01*
X165969Y169083D01*
X165816Y169374D01*
X165650Y169610D01*
X165470Y169818D01*
X165317Y169984D01*
X165192Y170095D01*
X165095Y170165D01*
X165081Y170192D01*
X165067D01*
X164776Y170373D01*
X164457Y170511D01*
X164152Y170608D01*
X163861Y170664D01*
X163597Y170705D01*
X163486Y170719D01*
X163389D01*
X163320Y170733D01*
X163209D01*
X162862Y170719D01*
X162543Y170664D01*
X162280Y170581D01*
X162044Y170497D01*
X161864Y170400D01*
X161725Y170331D01*
X161642Y170275D01*
X161614Y170248D01*
X161392Y170040D01*
X161184Y169804D01*
X161018Y169554D01*
X160879Y169305D01*
X160768Y169083D01*
X160727Y168972D01*
X160699Y168889D01*
X160671Y168819D01*
X160643Y168764D01*
X160630Y168736D01*
Y168722D01*
X159381Y169014D01*
X159465Y169263D01*
X159548Y169485D01*
X159659Y169693D01*
X159756Y169901D01*
X159867Y170081D01*
X159992Y170248D01*
X160103Y170414D01*
X160213Y170553D01*
X160324Y170664D01*
X160422Y170775D01*
X160519Y170872D01*
X160588Y170941D01*
X160657Y171010D01*
X160713Y171052D01*
X160740Y171066D01*
X160754Y171080D01*
X160949Y171205D01*
X161143Y171329D01*
X161337Y171427D01*
X161545Y171510D01*
X161961Y171635D01*
X162335Y171718D01*
X162516Y171759D01*
X162668Y171773D01*
X162821Y171787D01*
X162945Y171801D01*
X163043Y171815D01*
X163181D01*
X163639Y171787D01*
D02*
G37*
G36*
X151074Y165435D02*
Y164354D01*
X146900D01*
Y162052D01*
X145721D01*
Y164354D01*
X144417D01*
Y165435D01*
X145721D01*
Y171649D01*
X146678D01*
X151074Y165435D01*
D02*
G37*
G36*
X173433Y171312D02*
X173807Y171243D01*
X174126Y171132D01*
X174404Y171021D01*
X174528Y170952D01*
X174625Y170896D01*
X174722Y170841D01*
X174792Y170785D01*
X174847Y170744D01*
X174889Y170716D01*
X174917Y170702D01*
X174931Y170688D01*
X175194Y170425D01*
X175402Y170133D01*
X175569Y169828D01*
X175707Y169523D01*
X175790Y169260D01*
X175832Y169149D01*
X175860Y169052D01*
X175874Y168969D01*
X175888Y168913D01*
X175901Y168871D01*
Y168858D01*
X174722Y168650D01*
X174667Y168955D01*
X174584Y169218D01*
X174487Y169440D01*
X174390Y169620D01*
X174293Y169759D01*
X174209Y169856D01*
X174154Y169925D01*
X174140Y169939D01*
X173960Y170078D01*
X173766Y170189D01*
X173585Y170258D01*
X173405Y170314D01*
X173239Y170341D01*
X173114Y170369D01*
X173003D01*
X172753Y170355D01*
X172531Y170300D01*
X172337Y170231D01*
X172171Y170161D01*
X172046Y170078D01*
X171949Y170009D01*
X171880Y169953D01*
X171866Y169939D01*
X171713Y169773D01*
X171602Y169593D01*
X171533Y169412D01*
X171477Y169246D01*
X171450Y169093D01*
X171422Y168982D01*
Y168899D01*
Y168885D01*
Y168871D01*
Y168719D01*
X171450Y168580D01*
X171519Y168344D01*
X171616Y168137D01*
X171727Y167956D01*
X171838Y167831D01*
X171935Y167734D01*
X172004Y167679D01*
X172018Y167665D01*
X172032D01*
X172268Y167540D01*
X172490Y167443D01*
X172726Y167374D01*
X172934Y167332D01*
X173114Y167304D01*
X173266Y167277D01*
X173447D01*
X173502Y167290D01*
X173571D01*
X173710Y166250D01*
X173530Y166292D01*
X173363Y166320D01*
X173225Y166347D01*
X173100Y166361D01*
X173003Y166375D01*
X172878D01*
X172587Y166347D01*
X172323Y166292D01*
X172087Y166209D01*
X171893Y166112D01*
X171741Y166015D01*
X171630Y165931D01*
X171560Y165876D01*
X171533Y165848D01*
X171353Y165640D01*
X171214Y165418D01*
X171117Y165196D01*
X171061Y164974D01*
X171020Y164794D01*
X171006Y164642D01*
X170992Y164586D01*
Y164545D01*
Y164517D01*
Y164503D01*
X171020Y164198D01*
X171089Y163920D01*
X171172Y163685D01*
X171283Y163477D01*
X171394Y163310D01*
X171477Y163185D01*
X171547Y163102D01*
X171574Y163074D01*
X171796Y162880D01*
X172032Y162742D01*
X172268Y162645D01*
X172490Y162575D01*
X172684Y162534D01*
X172836Y162520D01*
X172892Y162506D01*
X172975D01*
X173225Y162520D01*
X173461Y162575D01*
X173668Y162645D01*
X173835Y162728D01*
X173974Y162797D01*
X174085Y162866D01*
X174140Y162922D01*
X174168Y162936D01*
X174334Y163130D01*
X174473Y163352D01*
X174598Y163588D01*
X174695Y163837D01*
X174764Y164045D01*
X174792Y164142D01*
X174806Y164226D01*
X174820Y164295D01*
X174834Y164350D01*
X174847Y164378D01*
Y164392D01*
X176026Y164239D01*
X175998Y164018D01*
X175957Y163810D01*
X175832Y163421D01*
X175679Y163088D01*
X175596Y162950D01*
X175513Y162811D01*
X175430Y162686D01*
X175347Y162589D01*
X175277Y162492D01*
X175208Y162423D01*
X175166Y162367D01*
X175125Y162326D01*
X175097Y162298D01*
X175083Y162284D01*
X174917Y162159D01*
X174750Y162034D01*
X174584Y161937D01*
X174404Y161854D01*
X174057Y161715D01*
X173724Y161632D01*
X173571Y161604D01*
X173433Y161577D01*
X173308Y161563D01*
X173197Y161549D01*
X173114Y161535D01*
X172989D01*
X172726Y161549D01*
X172490Y161577D01*
X172254Y161618D01*
X172032Y161674D01*
X171824Y161743D01*
X171644Y161812D01*
X171464Y161896D01*
X171311Y161979D01*
X171158Y162048D01*
X171033Y162132D01*
X170923Y162201D01*
X170839Y162270D01*
X170770Y162326D01*
X170715Y162367D01*
X170687Y162395D01*
X170673Y162409D01*
X170506Y162575D01*
X170368Y162756D01*
X170243Y162936D01*
X170132Y163116D01*
X170049Y163283D01*
X169966Y163463D01*
X169855Y163796D01*
X169827Y163948D01*
X169799Y164087D01*
X169771Y164212D01*
X169758Y164323D01*
X169744Y164406D01*
Y164475D01*
Y164517D01*
Y164531D01*
X169758Y164863D01*
X169813Y165169D01*
X169896Y165432D01*
X169979Y165654D01*
X170063Y165834D01*
X170146Y165973D01*
X170201Y166056D01*
X170215Y166084D01*
X170410Y166292D01*
X170618Y166472D01*
X170839Y166611D01*
X171061Y166722D01*
X171255Y166805D01*
X171408Y166861D01*
X171464Y166874D01*
X171505Y166888D01*
X171533Y166902D01*
X171547D01*
X171311Y167027D01*
X171117Y167152D01*
X170950Y167290D01*
X170812Y167415D01*
X170701Y167526D01*
X170618Y167623D01*
X170576Y167679D01*
X170562Y167707D01*
X170451Y167901D01*
X170368Y168095D01*
X170299Y168289D01*
X170257Y168469D01*
X170229Y168622D01*
X170215Y168733D01*
Y168816D01*
Y168844D01*
X170229Y169079D01*
X170271Y169315D01*
X170326Y169523D01*
X170396Y169704D01*
X170465Y169856D01*
X170520Y169981D01*
X170562Y170050D01*
X170576Y170078D01*
X170715Y170286D01*
X170881Y170466D01*
X171047Y170619D01*
X171214Y170758D01*
X171353Y170855D01*
X171477Y170938D01*
X171560Y170979D01*
X171574Y170993D01*
X171588D01*
X171838Y171104D01*
X172087Y171187D01*
X172337Y171257D01*
X172559Y171299D01*
X172739Y171326D01*
X172892Y171340D01*
X173239D01*
X173433Y171312D01*
D02*
G37*
G36*
X179965Y171104D02*
X180117Y170882D01*
X180298Y170660D01*
X180464Y170466D01*
X180630Y170300D01*
X180755Y170161D01*
X180811Y170120D01*
X180852Y170078D01*
X180866Y170064D01*
X180880Y170050D01*
X181171Y169814D01*
X181463Y169593D01*
X181740Y169398D01*
X182017Y169246D01*
X182253Y169107D01*
X182350Y169052D01*
X182433Y169010D01*
X182503Y168969D01*
X182558Y168955D01*
X182586Y168927D01*
X182600D01*
Y167790D01*
X182392Y167873D01*
X182184Y167970D01*
X181976Y168067D01*
X181782Y168164D01*
X181615Y168247D01*
X181476Y168317D01*
X181393Y168372D01*
X181379Y168386D01*
X181366D01*
X181116Y168539D01*
X180894Y168691D01*
X180700Y168830D01*
X180547Y168955D01*
X180409Y169052D01*
X180325Y169135D01*
X180256Y169191D01*
X180242Y169204D01*
Y161702D01*
X179063D01*
Y171340D01*
X179826D01*
X179965Y171104D01*
D02*
G37*
G36*
X189007Y171437D02*
X189451Y171368D01*
X189839Y171285D01*
X190019Y171229D01*
X190186Y171174D01*
X190338Y171118D01*
X190477Y171063D01*
X190588Y171021D01*
X190699Y170979D01*
X190768Y170938D01*
X190824Y170910D01*
X190865Y170896D01*
X190879Y170882D01*
X191254Y170647D01*
X191573Y170369D01*
X191850Y170092D01*
X192086Y169814D01*
X192266Y169565D01*
X192335Y169454D01*
X192391Y169357D01*
X192446Y169287D01*
X192474Y169232D01*
X192488Y169191D01*
X192502Y169177D01*
X192696Y168747D01*
X192835Y168303D01*
X192932Y167859D01*
X193001Y167457D01*
X193029Y167277D01*
X193043Y167096D01*
X193057Y166958D01*
Y166819D01*
X193070Y166722D01*
Y166639D01*
Y166583D01*
Y166569D01*
X193043Y166070D01*
X192987Y165585D01*
X192918Y165155D01*
X192862Y164947D01*
X192821Y164766D01*
X192779Y164600D01*
X192724Y164447D01*
X192682Y164309D01*
X192654Y164198D01*
X192613Y164115D01*
X192599Y164045D01*
X192571Y164004D01*
Y163990D01*
X192363Y163574D01*
X192127Y163199D01*
X191878Y162880D01*
X191753Y162756D01*
X191642Y162631D01*
X191531Y162520D01*
X191420Y162423D01*
X191323Y162339D01*
X191240Y162284D01*
X191184Y162229D01*
X191129Y162187D01*
X191101Y162173D01*
X191087Y162159D01*
X190893Y162048D01*
X190699Y161951D01*
X190283Y161799D01*
X189867Y161688D01*
X189465Y161618D01*
X189270Y161591D01*
X189104Y161563D01*
X188951Y161549D01*
X188827D01*
X188716Y161535D01*
X188563D01*
X188286Y161549D01*
X188022Y161577D01*
X187773Y161604D01*
X187537Y161660D01*
X187315Y161729D01*
X187107Y161799D01*
X186913Y161868D01*
X186733Y161951D01*
X186580Y162020D01*
X186427Y162090D01*
X186317Y162159D01*
X186206Y162229D01*
X186136Y162284D01*
X186067Y162312D01*
X186039Y162339D01*
X186025Y162353D01*
X185831Y162520D01*
X185665Y162686D01*
X185512Y162880D01*
X185360Y163074D01*
X185110Y163463D01*
X184916Y163851D01*
X184833Y164031D01*
X184763Y164198D01*
X184708Y164350D01*
X184666Y164475D01*
X184625Y164586D01*
X184597Y164669D01*
X184583Y164725D01*
Y164739D01*
X185859Y165058D01*
X185914Y164836D01*
X185984Y164628D01*
X186053Y164434D01*
X186122Y164253D01*
X186206Y164087D01*
X186289Y163948D01*
X186386Y163810D01*
X186469Y163685D01*
X186538Y163574D01*
X186622Y163491D01*
X186691Y163407D01*
X186746Y163338D01*
X186802Y163296D01*
X186843Y163255D01*
X186857Y163241D01*
X186871Y163227D01*
X187010Y163116D01*
X187162Y163033D01*
X187468Y162880D01*
X187759Y162769D01*
X188050Y162700D01*
X188300Y162645D01*
X188397Y162631D01*
X188494D01*
X188577Y162617D01*
X188674D01*
X188993Y162631D01*
X189298Y162686D01*
X189576Y162756D01*
X189825Y162839D01*
X190019Y162922D01*
X190103Y162964D01*
X190172Y162991D01*
X190227Y163019D01*
X190269Y163047D01*
X190297Y163061D01*
X190311D01*
X190574Y163255D01*
X190796Y163463D01*
X190990Y163699D01*
X191143Y163920D01*
X191268Y164115D01*
X191351Y164281D01*
X191378Y164350D01*
X191406Y164392D01*
X191420Y164420D01*
Y164434D01*
X191531Y164794D01*
X191614Y165155D01*
X191684Y165515D01*
X191725Y165848D01*
X191739Y166001D01*
X191753Y166139D01*
Y166264D01*
X191767Y166361D01*
Y166444D01*
Y166514D01*
Y166556D01*
Y166569D01*
X191753Y166930D01*
X191725Y167263D01*
X191670Y167568D01*
X191614Y167845D01*
X191573Y168081D01*
X191545Y168178D01*
X191517Y168261D01*
X191503Y168331D01*
X191489Y168372D01*
X191476Y168400D01*
Y168414D01*
X191337Y168733D01*
X191184Y169024D01*
X191018Y169260D01*
X190838Y169468D01*
X190685Y169634D01*
X190560Y169745D01*
X190463Y169814D01*
X190449Y169842D01*
X190435D01*
X190144Y170023D01*
X189825Y170161D01*
X189520Y170258D01*
X189229Y170314D01*
X188965Y170355D01*
X188854Y170369D01*
X188757D01*
X188688Y170383D01*
X188577D01*
X188230Y170369D01*
X187911Y170314D01*
X187648Y170231D01*
X187412Y170147D01*
X187232Y170050D01*
X187093Y169981D01*
X187010Y169925D01*
X186982Y169898D01*
X186760Y169690D01*
X186552Y169454D01*
X186386Y169204D01*
X186247Y168955D01*
X186136Y168733D01*
X186095Y168622D01*
X186067Y168539D01*
X186039Y168469D01*
X186011Y168414D01*
X185998Y168386D01*
Y168372D01*
X184749Y168664D01*
X184833Y168913D01*
X184916Y169135D01*
X185027Y169343D01*
X185124Y169551D01*
X185235Y169731D01*
X185360Y169898D01*
X185471Y170064D01*
X185581Y170203D01*
X185692Y170314D01*
X185790Y170425D01*
X185887Y170522D01*
X185956Y170591D01*
X186025Y170660D01*
X186081Y170702D01*
X186108Y170716D01*
X186122Y170730D01*
X186317Y170855D01*
X186511Y170979D01*
X186705Y171077D01*
X186913Y171160D01*
X187329Y171285D01*
X187703Y171368D01*
X187884Y171409D01*
X188036Y171423D01*
X188189Y171437D01*
X188314Y171451D01*
X188411Y171465D01*
X188549D01*
X189007Y171437D01*
D02*
G37*
G36*
X202881Y349846D02*
X203116Y350012D01*
X203214Y350095D01*
X203311Y350165D01*
X203394Y350234D01*
X203449Y350289D01*
X203491Y350331D01*
X203505Y350345D01*
X203574Y350414D01*
X203643Y350498D01*
X203824Y350692D01*
X204032Y350914D01*
X204240Y351149D01*
X204420Y351371D01*
X204503Y351468D01*
X204586Y351552D01*
X204642Y351621D01*
X204683Y351676D01*
X204711Y351704D01*
X204725Y351718D01*
X204919Y351940D01*
X205100Y352162D01*
X205280Y352356D01*
X205432Y352536D01*
X205585Y352703D01*
X205724Y352841D01*
X205849Y352980D01*
X205959Y353091D01*
X206070Y353202D01*
X206154Y353285D01*
X206223Y353354D01*
X206292Y353424D01*
X206376Y353493D01*
X206403Y353521D01*
X206639Y353715D01*
X206847Y353881D01*
X207055Y354020D01*
X207221Y354131D01*
X207374Y354214D01*
X207485Y354270D01*
X207554Y354297D01*
X207582Y354311D01*
X207790Y354394D01*
X207998Y354450D01*
X208192Y354506D01*
X208359Y354533D01*
X208511Y354547D01*
X208622Y354561D01*
X208692D01*
X208719D01*
X208927Y354547D01*
X209121Y354519D01*
X209316Y354492D01*
X209482Y354436D01*
X209815Y354297D01*
X210078Y354159D01*
X210203Y354076D01*
X210300Y354006D01*
X210397Y353937D01*
X210467Y353867D01*
X210522Y353812D01*
X210578Y353784D01*
X210592Y353757D01*
X210605Y353743D01*
X210744Y353590D01*
X210869Y353424D01*
X210966Y353243D01*
X211049Y353063D01*
X211188Y352703D01*
X211285Y352342D01*
X211313Y352189D01*
X211340Y352037D01*
X211354Y351898D01*
X211368Y351787D01*
X211382Y351690D01*
Y351552D01*
X211368Y351302D01*
X211354Y351066D01*
X211313Y350844D01*
X211271Y350636D01*
X211215Y350442D01*
X211160Y350262D01*
X211091Y350095D01*
X211021Y349943D01*
X210952Y349804D01*
X210883Y349693D01*
X210827Y349596D01*
X210772Y349513D01*
X210730Y349444D01*
X210688Y349402D01*
X210675Y349374D01*
X210661Y349360D01*
X210522Y349222D01*
X210370Y349097D01*
X210203Y348972D01*
X210037Y348875D01*
X209704Y348708D01*
X209371Y348597D01*
X209219Y348556D01*
X209066Y348514D01*
X208941Y348487D01*
X208830Y348459D01*
X208733Y348445D01*
X208664D01*
X208622Y348431D01*
X208608D01*
X208484Y349638D01*
X208802Y349665D01*
X209080Y349721D01*
X209329Y349804D01*
X209524Y349901D01*
X209690Y349984D01*
X209801Y350068D01*
X209870Y350123D01*
X209898Y350151D01*
X210065Y350359D01*
X210189Y350581D01*
X210286Y350816D01*
X210342Y351025D01*
X210383Y351219D01*
X210397Y351385D01*
X210411Y351441D01*
Y351524D01*
X210397Y351815D01*
X210342Y352079D01*
X210259Y352300D01*
X210175Y352495D01*
X210078Y352647D01*
X210009Y352744D01*
X209953Y352813D01*
X209926Y352841D01*
X209732Y353008D01*
X209538Y353133D01*
X209343Y353230D01*
X209149Y353285D01*
X208997Y353327D01*
X208858Y353340D01*
X208775Y353354D01*
X208761D01*
X208747D01*
X208497Y353327D01*
X208234Y353271D01*
X207998Y353174D01*
X207776Y353077D01*
X207596Y352966D01*
X207443Y352869D01*
X207388Y352841D01*
X207346Y352813D01*
X207332Y352786D01*
X207318D01*
X207166Y352675D01*
X207013Y352536D01*
X206847Y352384D01*
X206681Y352217D01*
X206348Y351870D01*
X206015Y351524D01*
X205862Y351343D01*
X205724Y351191D01*
X205599Y351038D01*
X205488Y350914D01*
X205405Y350816D01*
X205335Y350733D01*
X205294Y350678D01*
X205280Y350664D01*
X204989Y350317D01*
X204711Y349998D01*
X204462Y349735D01*
X204254Y349527D01*
X204073Y349346D01*
X203948Y349222D01*
X203865Y349152D01*
X203851Y349124D01*
X203838D01*
X203602Y348930D01*
X203380Y348778D01*
X203158Y348639D01*
X202964Y348528D01*
X202797Y348445D01*
X202673Y348390D01*
X202589Y348362D01*
X202575Y348348D01*
X202562D01*
X202409Y348292D01*
X202270Y348265D01*
X202132Y348237D01*
X202007Y348223D01*
X201896Y348209D01*
X201813D01*
X201757D01*
X201743D01*
Y354575D01*
X202881D01*
Y349846D01*
D02*
G37*
G36*
X211382Y344590D02*
X211146Y344451D01*
X210924Y344298D01*
X210702Y344118D01*
X210508Y343952D01*
X210342Y343785D01*
X210203Y343660D01*
X210161Y343605D01*
X210120Y343563D01*
X210106Y343549D01*
X210092Y343536D01*
X209856Y343244D01*
X209634Y342953D01*
X209440Y342676D01*
X209288Y342398D01*
X209149Y342163D01*
X209094Y342066D01*
X209052Y341982D01*
X209011Y341913D01*
X208997Y341857D01*
X208969Y341830D01*
Y341816D01*
X207832D01*
X207915Y342024D01*
X208012Y342232D01*
X208109Y342440D01*
X208206Y342634D01*
X208289Y342800D01*
X208359Y342939D01*
X208414Y343022D01*
X208428Y343036D01*
Y343050D01*
X208580Y343300D01*
X208733Y343522D01*
X208872Y343716D01*
X208997Y343868D01*
X209094Y344007D01*
X209177Y344090D01*
X209232Y344160D01*
X209246Y344174D01*
X201743D01*
Y345352D01*
X211382D01*
Y344590D01*
D02*
G37*
G36*
X205100Y338557D02*
X204878Y338501D01*
X204670Y338432D01*
X204475Y338363D01*
X204295Y338293D01*
X204129Y338210D01*
X203990Y338127D01*
X203851Y338030D01*
X203727Y337947D01*
X203616Y337877D01*
X203532Y337794D01*
X203449Y337725D01*
X203380Y337669D01*
X203338Y337614D01*
X203297Y337572D01*
X203283Y337558D01*
X203269Y337544D01*
X203158Y337406D01*
X203075Y337253D01*
X202922Y336948D01*
X202811Y336657D01*
X202742Y336366D01*
X202687Y336116D01*
X202673Y336019D01*
Y335922D01*
X202659Y335839D01*
Y335742D01*
X202673Y335423D01*
X202728Y335117D01*
X202797Y334840D01*
X202881Y334590D01*
X202964Y334396D01*
X203005Y334313D01*
X203033Y334244D01*
X203061Y334188D01*
X203089Y334147D01*
X203102Y334119D01*
Y334105D01*
X203297Y333842D01*
X203505Y333620D01*
X203741Y333425D01*
X203962Y333273D01*
X204156Y333148D01*
X204323Y333065D01*
X204392Y333037D01*
X204434Y333009D01*
X204462Y332996D01*
X204475D01*
X204836Y332885D01*
X205197Y332801D01*
X205557Y332732D01*
X205890Y332691D01*
X206043Y332677D01*
X206181Y332663D01*
X206306D01*
X206403Y332649D01*
X206486D01*
X206556D01*
X206597D01*
X206611D01*
X206972Y332663D01*
X207305Y332691D01*
X207610Y332746D01*
X207887Y332801D01*
X208123Y332843D01*
X208220Y332871D01*
X208303Y332898D01*
X208372Y332912D01*
X208414Y332926D01*
X208442Y332940D01*
X208456D01*
X208775Y333079D01*
X209066Y333231D01*
X209302Y333398D01*
X209510Y333578D01*
X209676Y333731D01*
X209787Y333855D01*
X209856Y333952D01*
X209884Y333966D01*
Y333980D01*
X210065Y334272D01*
X210203Y334590D01*
X210300Y334896D01*
X210356Y335187D01*
X210397Y335450D01*
X210411Y335561D01*
Y335658D01*
X210425Y335728D01*
Y335839D01*
X210411Y336185D01*
X210356Y336504D01*
X210273Y336768D01*
X210189Y337004D01*
X210092Y337184D01*
X210023Y337323D01*
X209967Y337406D01*
X209940Y337434D01*
X209732Y337655D01*
X209496Y337863D01*
X209246Y338030D01*
X208997Y338168D01*
X208775Y338279D01*
X208664Y338321D01*
X208580Y338349D01*
X208511Y338377D01*
X208456Y338404D01*
X208428Y338418D01*
X208414D01*
X208705Y339666D01*
X208955Y339583D01*
X209177Y339500D01*
X209385Y339389D01*
X209593Y339292D01*
X209773Y339181D01*
X209940Y339056D01*
X210106Y338945D01*
X210245Y338834D01*
X210356Y338723D01*
X210467Y338626D01*
X210564Y338529D01*
X210633Y338460D01*
X210702Y338390D01*
X210744Y338335D01*
X210758Y338307D01*
X210772Y338293D01*
X210897Y338099D01*
X211021Y337905D01*
X211118Y337711D01*
X211202Y337503D01*
X211327Y337087D01*
X211410Y336712D01*
X211451Y336532D01*
X211465Y336380D01*
X211479Y336227D01*
X211493Y336102D01*
X211507Y336005D01*
Y335866D01*
X211479Y335409D01*
X211410Y334965D01*
X211327Y334577D01*
X211271Y334396D01*
X211215Y334230D01*
X211160Y334077D01*
X211105Y333939D01*
X211063Y333828D01*
X211021Y333717D01*
X210980Y333647D01*
X210952Y333592D01*
X210938Y333550D01*
X210924Y333536D01*
X210688Y333162D01*
X210411Y332843D01*
X210134Y332566D01*
X209856Y332330D01*
X209607Y332150D01*
X209496Y332080D01*
X209399Y332025D01*
X209329Y331969D01*
X209274Y331942D01*
X209232Y331928D01*
X209219Y331914D01*
X208789Y331720D01*
X208345Y331581D01*
X207901Y331484D01*
X207499Y331415D01*
X207318Y331387D01*
X207138Y331373D01*
X206999Y331359D01*
X206861D01*
X206764Y331345D01*
X206681D01*
X206625D01*
X206611D01*
X206112Y331373D01*
X205627Y331428D01*
X205197Y331498D01*
X204989Y331553D01*
X204808Y331595D01*
X204642Y331637D01*
X204489Y331692D01*
X204351Y331734D01*
X204240Y331761D01*
X204156Y331803D01*
X204087Y331817D01*
X204046Y331844D01*
X204032D01*
X203616Y332052D01*
X203241Y332288D01*
X202922Y332538D01*
X202797Y332663D01*
X202673Y332774D01*
X202562Y332885D01*
X202465Y332996D01*
X202381Y333093D01*
X202326Y333176D01*
X202270Y333231D01*
X202229Y333287D01*
X202215Y333315D01*
X202201Y333328D01*
X202090Y333523D01*
X201993Y333717D01*
X201840Y334133D01*
X201730Y334549D01*
X201660Y334951D01*
X201632Y335145D01*
X201605Y335312D01*
X201591Y335464D01*
Y335589D01*
X201577Y335700D01*
Y335853D01*
X201591Y336130D01*
X201619Y336393D01*
X201646Y336643D01*
X201702Y336879D01*
X201771Y337101D01*
X201840Y337309D01*
X201910Y337503D01*
X201993Y337683D01*
X202062Y337836D01*
X202132Y337988D01*
X202201Y338099D01*
X202270Y338210D01*
X202326Y338279D01*
X202354Y338349D01*
X202381Y338377D01*
X202395Y338390D01*
X202562Y338585D01*
X202728Y338751D01*
X202922Y338904D01*
X203116Y339056D01*
X203505Y339306D01*
X203893Y339500D01*
X204073Y339583D01*
X204240Y339652D01*
X204392Y339708D01*
X204517Y339749D01*
X204628Y339791D01*
X204711Y339819D01*
X204767Y339833D01*
X204781D01*
X205100Y338557D01*
D02*
G37*
G36*
X198132Y350944D02*
X197896Y350805D01*
X197674Y350653D01*
X197452Y350473D01*
X197258Y350306D01*
X197092Y350140D01*
X196953Y350015D01*
X196912Y349959D01*
X196870Y349918D01*
X196856Y349904D01*
X196842Y349890D01*
X196606Y349599D01*
X196385Y349308D01*
X196190Y349030D01*
X196038Y348753D01*
X195899Y348517D01*
X195844Y348420D01*
X195802Y348337D01*
X195760Y348268D01*
X195747Y348212D01*
X195719Y348184D01*
Y348170D01*
X194582D01*
X194665Y348378D01*
X194762Y348587D01*
X194859Y348795D01*
X194956Y348989D01*
X195039Y349155D01*
X195109Y349294D01*
X195164Y349377D01*
X195178Y349391D01*
Y349405D01*
X195331Y349654D01*
X195483Y349876D01*
X195622Y350070D01*
X195747Y350223D01*
X195844Y350362D01*
X195927Y350445D01*
X195982Y350514D01*
X195996Y350528D01*
X188493D01*
Y351707D01*
X198132D01*
Y350944D01*
D02*
G37*
G36*
Y343483D02*
X197896Y343344D01*
X197674Y343192D01*
X197452Y343011D01*
X197258Y342845D01*
X197092Y342679D01*
X196953Y342554D01*
X196912Y342498D01*
X196870Y342457D01*
X196856Y342443D01*
X196842Y342429D01*
X196606Y342138D01*
X196385Y341847D01*
X196190Y341569D01*
X196038Y341292D01*
X195899Y341056D01*
X195844Y340959D01*
X195802Y340876D01*
X195760Y340806D01*
X195747Y340751D01*
X195719Y340723D01*
Y340709D01*
X194582D01*
X194665Y340917D01*
X194762Y341125D01*
X194859Y341333D01*
X194956Y341527D01*
X195039Y341694D01*
X195109Y341833D01*
X195164Y341916D01*
X195178Y341930D01*
Y341944D01*
X195331Y342193D01*
X195483Y342415D01*
X195622Y342609D01*
X195747Y342762D01*
X195844Y342901D01*
X195927Y342984D01*
X195982Y343053D01*
X195996Y343067D01*
X188493D01*
Y344246D01*
X198132D01*
Y343483D01*
D02*
G37*
G36*
X191850Y337450D02*
X191628Y337395D01*
X191420Y337325D01*
X191225Y337256D01*
X191045Y337187D01*
X190879Y337104D01*
X190740Y337020D01*
X190601Y336923D01*
X190477Y336840D01*
X190366Y336771D01*
X190282Y336687D01*
X190199Y336618D01*
X190130Y336563D01*
X190088Y336507D01*
X190047Y336465D01*
X190033Y336452D01*
X190019Y336438D01*
X189908Y336299D01*
X189825Y336147D01*
X189672Y335841D01*
X189561Y335550D01*
X189492Y335259D01*
X189436Y335009D01*
X189423Y334912D01*
Y334815D01*
X189409Y334732D01*
Y334635D01*
X189423Y334316D01*
X189478Y334011D01*
X189547Y333733D01*
X189631Y333484D01*
X189714Y333290D01*
X189755Y333206D01*
X189783Y333137D01*
X189811Y333082D01*
X189839Y333040D01*
X189853Y333012D01*
Y332998D01*
X190047Y332735D01*
X190255Y332513D01*
X190490Y332319D01*
X190712Y332166D01*
X190907Y332042D01*
X191073Y331958D01*
X191142Y331931D01*
X191184Y331903D01*
X191212Y331889D01*
X191225D01*
X191586Y331778D01*
X191947Y331695D01*
X192307Y331625D01*
X192640Y331584D01*
X192793Y331570D01*
X192931Y331556D01*
X193056D01*
X193153Y331542D01*
X193236D01*
X193306D01*
X193347D01*
X193361D01*
X193722Y331556D01*
X194055Y331584D01*
X194360Y331639D01*
X194637Y331695D01*
X194873Y331736D01*
X194970Y331764D01*
X195053Y331792D01*
X195123Y331806D01*
X195164Y331820D01*
X195192Y331833D01*
X195206D01*
X195525Y331972D01*
X195816Y332125D01*
X196052Y332291D01*
X196260Y332471D01*
X196426Y332624D01*
X196537Y332749D01*
X196606Y332846D01*
X196634Y332860D01*
Y332874D01*
X196814Y333165D01*
X196953Y333484D01*
X197050Y333789D01*
X197106Y334080D01*
X197147Y334344D01*
X197161Y334455D01*
Y334552D01*
X197175Y334621D01*
Y334732D01*
X197161Y335079D01*
X197106Y335398D01*
X197022Y335661D01*
X196939Y335897D01*
X196842Y336077D01*
X196773Y336216D01*
X196717Y336299D01*
X196690Y336327D01*
X196482Y336549D01*
X196246Y336757D01*
X195996Y336923D01*
X195747Y337062D01*
X195525Y337173D01*
X195414Y337214D01*
X195331Y337242D01*
X195261Y337270D01*
X195206Y337298D01*
X195178Y337312D01*
X195164D01*
X195455Y338560D01*
X195705Y338476D01*
X195927Y338393D01*
X196135Y338282D01*
X196343Y338185D01*
X196523Y338074D01*
X196690Y337949D01*
X196856Y337839D01*
X196995Y337728D01*
X197106Y337617D01*
X197217Y337519D01*
X197314Y337422D01*
X197383Y337353D01*
X197452Y337284D01*
X197494Y337228D01*
X197508Y337201D01*
X197522Y337187D01*
X197647Y336992D01*
X197771Y336798D01*
X197868Y336604D01*
X197952Y336396D01*
X198076Y335980D01*
X198160Y335606D01*
X198201Y335425D01*
X198215Y335273D01*
X198229Y335120D01*
X198243Y334995D01*
X198257Y334898D01*
Y334760D01*
X198229Y334302D01*
X198160Y333858D01*
X198076Y333470D01*
X198021Y333290D01*
X197966Y333123D01*
X197910Y332971D01*
X197855Y332832D01*
X197813Y332721D01*
X197771Y332610D01*
X197730Y332541D01*
X197702Y332485D01*
X197688Y332444D01*
X197674Y332430D01*
X197439Y332055D01*
X197161Y331736D01*
X196884Y331459D01*
X196606Y331223D01*
X196357Y331043D01*
X196246Y330974D01*
X196149Y330918D01*
X196079Y330863D01*
X196024Y330835D01*
X195982Y330821D01*
X195968Y330807D01*
X195539Y330613D01*
X195095Y330474D01*
X194651Y330377D01*
X194249Y330308D01*
X194069Y330280D01*
X193888Y330266D01*
X193750Y330252D01*
X193611D01*
X193514Y330239D01*
X193431D01*
X193375D01*
X193361D01*
X192862Y330266D01*
X192377Y330322D01*
X191947Y330391D01*
X191739Y330447D01*
X191558Y330488D01*
X191392Y330530D01*
X191239Y330585D01*
X191101Y330627D01*
X190990Y330655D01*
X190907Y330696D01*
X190837Y330710D01*
X190796Y330738D01*
X190782D01*
X190366Y330946D01*
X189991Y331182D01*
X189672Y331431D01*
X189547Y331556D01*
X189423Y331667D01*
X189312Y331778D01*
X189215Y331889D01*
X189131Y331986D01*
X189076Y332069D01*
X189020Y332125D01*
X188979Y332180D01*
X188965Y332208D01*
X188951Y332222D01*
X188840Y332416D01*
X188743Y332610D01*
X188591Y333026D01*
X188479Y333442D01*
X188410Y333844D01*
X188382Y334039D01*
X188355Y334205D01*
X188341Y334357D01*
Y334482D01*
X188327Y334593D01*
Y334746D01*
X188341Y335023D01*
X188369Y335287D01*
X188396Y335536D01*
X188452Y335772D01*
X188521Y335994D01*
X188591Y336202D01*
X188660Y336396D01*
X188743Y336576D01*
X188812Y336729D01*
X188882Y336882D01*
X188951Y336992D01*
X189020Y337104D01*
X189076Y337173D01*
X189104Y337242D01*
X189131Y337270D01*
X189145Y337284D01*
X189312Y337478D01*
X189478Y337644D01*
X189672Y337797D01*
X189866Y337949D01*
X190255Y338199D01*
X190643Y338393D01*
X190823Y338476D01*
X190990Y338546D01*
X191142Y338601D01*
X191267Y338643D01*
X191378Y338685D01*
X191461Y338712D01*
X191517Y338726D01*
X191531D01*
X191850Y337450D01*
D02*
G37*
G36*
X412376Y395618D02*
X412820Y395549D01*
X413208Y395465D01*
X413389Y395410D01*
X413555Y395354D01*
X413708Y395299D01*
X413846Y395243D01*
X413957Y395202D01*
X414068Y395160D01*
X414137Y395119D01*
X414193Y395091D01*
X414235Y395077D01*
X414248Y395063D01*
X414623Y394827D01*
X414942Y394550D01*
X415219Y394273D01*
X415455Y393995D01*
X415635Y393746D01*
X415705Y393635D01*
X415760Y393538D01*
X415816Y393468D01*
X415843Y393413D01*
X415857Y393371D01*
X415871Y393357D01*
X416065Y392927D01*
X416204Y392484D01*
X416301Y392040D01*
X416370Y391638D01*
X416398Y391457D01*
X416412Y391277D01*
X416426Y391138D01*
Y391000D01*
X416440Y390903D01*
Y390819D01*
Y390764D01*
Y390750D01*
X416412Y390251D01*
X416356Y389765D01*
X416287Y389336D01*
X416232Y389128D01*
X416190Y388947D01*
X416148Y388781D01*
X416093Y388628D01*
X416051Y388489D01*
X416024Y388379D01*
X415982Y388295D01*
X415968Y388226D01*
X415940Y388184D01*
Y388171D01*
X415732Y387755D01*
X415497Y387380D01*
X415247Y387061D01*
X415122Y386936D01*
X415011Y386811D01*
X414900Y386701D01*
X414789Y386603D01*
X414692Y386520D01*
X414609Y386465D01*
X414554Y386409D01*
X414498Y386368D01*
X414470Y386354D01*
X414456Y386340D01*
X414262Y386229D01*
X414068Y386132D01*
X413652Y385979D01*
X413236Y385868D01*
X412834Y385799D01*
X412640Y385771D01*
X412473Y385744D01*
X412321Y385730D01*
X412196D01*
X412085Y385716D01*
X411932D01*
X411655Y385730D01*
X411392Y385757D01*
X411142Y385785D01*
X410906Y385841D01*
X410684Y385910D01*
X410476Y385979D01*
X410282Y386049D01*
X410102Y386132D01*
X409949Y386201D01*
X409797Y386271D01*
X409686Y386340D01*
X409575Y386409D01*
X409506Y386465D01*
X409436Y386493D01*
X409408Y386520D01*
X409394Y386534D01*
X409200Y386701D01*
X409034Y386867D01*
X408881Y387061D01*
X408729Y387255D01*
X408479Y387644D01*
X408285Y388032D01*
X408202Y388212D01*
X408133Y388379D01*
X408077Y388531D01*
X408035Y388656D01*
X407994Y388767D01*
X407966Y388850D01*
X407952Y388906D01*
Y388919D01*
X409228Y389238D01*
X409284Y389016D01*
X409353Y388809D01*
X409422Y388614D01*
X409492Y388434D01*
X409575Y388268D01*
X409658Y388129D01*
X409755Y387990D01*
X409838Y387865D01*
X409908Y387755D01*
X409991Y387671D01*
X410060Y387588D01*
X410116Y387519D01*
X410171Y387477D01*
X410213Y387435D01*
X410227Y387422D01*
X410241Y387408D01*
X410379Y387297D01*
X410532Y387214D01*
X410837Y387061D01*
X411128Y386950D01*
X411419Y386881D01*
X411669Y386825D01*
X411766Y386811D01*
X411863D01*
X411946Y386798D01*
X412043D01*
X412362Y386811D01*
X412668Y386867D01*
X412945Y386936D01*
X413194Y387020D01*
X413389Y387103D01*
X413472Y387144D01*
X413541Y387172D01*
X413597Y387200D01*
X413638Y387228D01*
X413666Y387241D01*
X413680D01*
X413943Y387435D01*
X414165Y387644D01*
X414359Y387879D01*
X414512Y388101D01*
X414637Y388295D01*
X414720Y388462D01*
X414748Y388531D01*
X414775Y388573D01*
X414789Y388601D01*
Y388614D01*
X414900Y388975D01*
X414983Y389336D01*
X415053Y389696D01*
X415094Y390029D01*
X415108Y390182D01*
X415122Y390320D01*
Y390445D01*
X415136Y390542D01*
Y390625D01*
Y390695D01*
Y390736D01*
Y390750D01*
X415122Y391111D01*
X415094Y391443D01*
X415039Y391749D01*
X414983Y392026D01*
X414942Y392262D01*
X414914Y392359D01*
X414886Y392442D01*
X414873Y392511D01*
X414859Y392553D01*
X414845Y392581D01*
Y392595D01*
X414706Y392914D01*
X414554Y393205D01*
X414387Y393441D01*
X414207Y393649D01*
X414054Y393815D01*
X413929Y393926D01*
X413832Y393995D01*
X413819Y394023D01*
X413805D01*
X413513Y394203D01*
X413194Y394342D01*
X412889Y394439D01*
X412598Y394495D01*
X412335Y394536D01*
X412224Y394550D01*
X412127D01*
X412057Y394564D01*
X411946D01*
X411600Y394550D01*
X411281Y394495D01*
X411017Y394411D01*
X410781Y394328D01*
X410601Y394231D01*
X410462Y394162D01*
X410379Y394106D01*
X410351Y394078D01*
X410130Y393871D01*
X409921Y393635D01*
X409755Y393385D01*
X409616Y393135D01*
X409506Y392914D01*
X409464Y392803D01*
X409436Y392719D01*
X409408Y392650D01*
X409381Y392595D01*
X409367Y392567D01*
Y392553D01*
X408119Y392844D01*
X408202Y393094D01*
X408285Y393316D01*
X408396Y393524D01*
X408493Y393732D01*
X408604Y393912D01*
X408729Y394078D01*
X408840Y394245D01*
X408951Y394384D01*
X409062Y394495D01*
X409159Y394605D01*
X409256Y394703D01*
X409325Y394772D01*
X409394Y394841D01*
X409450Y394883D01*
X409478Y394897D01*
X409492Y394911D01*
X409686Y395035D01*
X409880Y395160D01*
X410074Y395257D01*
X410282Y395340D01*
X410698Y395465D01*
X411073Y395549D01*
X411253Y395590D01*
X411405Y395604D01*
X411558Y395618D01*
X411683Y395632D01*
X411780Y395646D01*
X411919D01*
X412376Y395618D01*
D02*
G37*
G36*
X403972Y395507D02*
X404194Y395493D01*
X404582Y395410D01*
X404762Y395354D01*
X404929Y395299D01*
X405081Y395230D01*
X405220Y395160D01*
X405331Y395091D01*
X405442Y395022D01*
X405539Y394966D01*
X405608Y394911D01*
X405664Y394869D01*
X405705Y394827D01*
X405733Y394813D01*
X405747Y394800D01*
X405872Y394661D01*
X405997Y394522D01*
X406094Y394370D01*
X406177Y394217D01*
X406316Y393926D01*
X406399Y393649D01*
X406454Y393413D01*
X406468Y393302D01*
X406482Y393219D01*
X406496Y393135D01*
Y393080D01*
Y393052D01*
Y393038D01*
X406482Y392789D01*
X406441Y392553D01*
X406385Y392345D01*
X406316Y392165D01*
X406260Y392026D01*
X406205Y391915D01*
X406163Y391860D01*
X406149Y391832D01*
X405997Y391665D01*
X405830Y391513D01*
X405650Y391374D01*
X405470Y391263D01*
X405303Y391180D01*
X405178Y391124D01*
X405123Y391097D01*
X405081Y391083D01*
X405068Y391069D01*
X405054D01*
X405373Y390972D01*
X405636Y390847D01*
X405872Y390695D01*
X406066Y390556D01*
X406219Y390417D01*
X406330Y390306D01*
X406385Y390237D01*
X406413Y390223D01*
Y390209D01*
X406565Y389960D01*
X406690Y389696D01*
X406773Y389446D01*
X406829Y389197D01*
X406857Y388975D01*
X406870Y388878D01*
Y388795D01*
X406884Y388739D01*
Y388684D01*
Y388656D01*
Y388642D01*
X406870Y388420D01*
X406843Y388198D01*
X406801Y387990D01*
X406746Y387782D01*
X406607Y387435D01*
X406538Y387269D01*
X406454Y387130D01*
X406371Y386992D01*
X406302Y386881D01*
X406219Y386784D01*
X406163Y386701D01*
X406108Y386631D01*
X406066Y386590D01*
X406038Y386562D01*
X406025Y386548D01*
X405858Y386395D01*
X405678Y386271D01*
X405484Y386160D01*
X405289Y386063D01*
X405109Y385993D01*
X404915Y385924D01*
X404541Y385827D01*
X404374Y385785D01*
X404222Y385757D01*
X404083Y385744D01*
X403958Y385730D01*
X403861Y385716D01*
X403722D01*
X403459Y385730D01*
X403223Y385757D01*
X402987Y385799D01*
X402765Y385841D01*
X402571Y385910D01*
X402377Y385979D01*
X402197Y386049D01*
X402044Y386132D01*
X401906Y386215D01*
X401781Y386284D01*
X401684Y386354D01*
X401587Y386423D01*
X401517Y386465D01*
X401476Y386506D01*
X401448Y386534D01*
X401434Y386548D01*
X401282Y386714D01*
X401143Y386881D01*
X401032Y387047D01*
X400935Y387228D01*
X400838Y387394D01*
X400768Y387574D01*
X400671Y387893D01*
X400630Y388046D01*
X400602Y388184D01*
X400588Y388309D01*
X400574Y388406D01*
X400560Y388489D01*
Y388559D01*
Y388601D01*
Y388614D01*
X400574Y388933D01*
X400630Y389225D01*
X400713Y389488D01*
X400796Y389710D01*
X400879Y389890D01*
X400962Y390029D01*
X401018Y390112D01*
X401032Y390126D01*
Y390140D01*
X401226Y390362D01*
X401434Y390556D01*
X401656Y390709D01*
X401864Y390847D01*
X402058Y390944D01*
X402225Y391014D01*
X402280Y391041D01*
X402322Y391055D01*
X402349Y391069D01*
X402363D01*
X402114Y391180D01*
X401906Y391305D01*
X401725Y391430D01*
X401573Y391554D01*
X401462Y391665D01*
X401379Y391749D01*
X401323Y391804D01*
X401309Y391832D01*
X401184Y392026D01*
X401101Y392220D01*
X401032Y392414D01*
X400990Y392608D01*
X400962Y392761D01*
X400949Y392886D01*
Y392969D01*
Y392983D01*
Y392997D01*
X400962Y393191D01*
X400976Y393371D01*
X401073Y393718D01*
X401198Y394023D01*
X401337Y394286D01*
X401476Y394495D01*
X401545Y394578D01*
X401600Y394661D01*
X401656Y394716D01*
X401698Y394758D01*
X401711Y394772D01*
X401725Y394786D01*
X401878Y394911D01*
X402030Y395035D01*
X402197Y395132D01*
X402363Y395216D01*
X402696Y395340D01*
X403029Y395424D01*
X403168Y395465D01*
X403306Y395479D01*
X403431Y395493D01*
X403542Y395507D01*
X403625Y395521D01*
X403750D01*
X403972Y395507D01*
D02*
G37*
G36*
X122096Y410328D02*
X122332Y410314D01*
X122554Y410272D01*
X122761Y410231D01*
X122956Y410175D01*
X123136Y410120D01*
X123302Y410050D01*
X123455Y409981D01*
X123594Y409912D01*
X123705Y409842D01*
X123802Y409787D01*
X123885Y409731D01*
X123954Y409690D01*
X123996Y409648D01*
X124024Y409634D01*
X124037Y409621D01*
X124176Y409482D01*
X124301Y409329D01*
X124426Y409163D01*
X124523Y408996D01*
X124689Y408664D01*
X124800Y408331D01*
X124842Y408178D01*
X124883Y408026D01*
X124911Y407901D01*
X124939Y407790D01*
X124953Y407693D01*
Y407623D01*
X124967Y407582D01*
Y407568D01*
X123760Y407443D01*
X123732Y407762D01*
X123677Y408040D01*
X123594Y408289D01*
X123497Y408483D01*
X123413Y408650D01*
X123330Y408761D01*
X123275Y408830D01*
X123247Y408858D01*
X123039Y409024D01*
X122817Y409149D01*
X122581Y409246D01*
X122373Y409301D01*
X122179Y409343D01*
X122013Y409357D01*
X121957Y409371D01*
X121874D01*
X121583Y409357D01*
X121319Y409301D01*
X121097Y409218D01*
X120903Y409135D01*
X120751Y409038D01*
X120653Y408969D01*
X120584Y408913D01*
X120556Y408885D01*
X120390Y408691D01*
X120265Y408497D01*
X120168Y408303D01*
X120113Y408109D01*
X120071Y407956D01*
X120057Y407818D01*
X120043Y407734D01*
Y407720D01*
Y407707D01*
X120071Y407457D01*
X120126Y407193D01*
X120224Y406958D01*
X120321Y406736D01*
X120432Y406556D01*
X120529Y406403D01*
X120556Y406348D01*
X120584Y406306D01*
X120612Y406292D01*
Y406278D01*
X120723Y406126D01*
X120862Y405973D01*
X121014Y405807D01*
X121180Y405640D01*
X121527Y405307D01*
X121874Y404975D01*
X122054Y404822D01*
X122207Y404683D01*
X122359Y404558D01*
X122484Y404448D01*
X122581Y404364D01*
X122664Y404295D01*
X122720Y404253D01*
X122734Y404240D01*
X123080Y403948D01*
X123399Y403671D01*
X123663Y403421D01*
X123871Y403213D01*
X124051Y403033D01*
X124176Y402908D01*
X124245Y402825D01*
X124273Y402811D01*
Y402797D01*
X124467Y402561D01*
X124620Y402340D01*
X124759Y402118D01*
X124869Y401923D01*
X124953Y401757D01*
X125008Y401632D01*
X125036Y401549D01*
X125050Y401535D01*
Y401521D01*
X125105Y401369D01*
X125133Y401230D01*
X125161Y401091D01*
X125175Y400967D01*
X125188Y400856D01*
Y400773D01*
Y400717D01*
Y400703D01*
X118823D01*
Y401840D01*
X123552D01*
X123386Y402076D01*
X123302Y402173D01*
X123233Y402270D01*
X123164Y402353D01*
X123108Y402409D01*
X123067Y402450D01*
X123053Y402464D01*
X122983Y402534D01*
X122900Y402603D01*
X122706Y402783D01*
X122484Y402991D01*
X122248Y403199D01*
X122027Y403380D01*
X121929Y403463D01*
X121846Y403546D01*
X121777Y403602D01*
X121721Y403643D01*
X121694Y403671D01*
X121680Y403685D01*
X121458Y403879D01*
X121236Y404059D01*
X121042Y404240D01*
X120862Y404392D01*
X120695Y404545D01*
X120556Y404683D01*
X120418Y404808D01*
X120307Y404919D01*
X120196Y405030D01*
X120113Y405113D01*
X120043Y405183D01*
X119974Y405252D01*
X119905Y405335D01*
X119877Y405363D01*
X119683Y405599D01*
X119516Y405807D01*
X119378Y406015D01*
X119267Y406181D01*
X119183Y406334D01*
X119128Y406445D01*
X119100Y406514D01*
X119086Y406542D01*
X119003Y406750D01*
X118948Y406958D01*
X118892Y407152D01*
X118864Y407318D01*
X118851Y407471D01*
X118837Y407582D01*
Y407651D01*
Y407679D01*
X118851Y407887D01*
X118878Y408081D01*
X118906Y408275D01*
X118961Y408442D01*
X119100Y408774D01*
X119239Y409038D01*
X119322Y409163D01*
X119391Y409260D01*
X119461Y409357D01*
X119530Y409426D01*
X119586Y409482D01*
X119613Y409537D01*
X119641Y409551D01*
X119655Y409565D01*
X119808Y409704D01*
X119974Y409828D01*
X120154Y409926D01*
X120335Y410009D01*
X120695Y410148D01*
X121056Y410245D01*
X121208Y410272D01*
X121361Y410300D01*
X121500Y410314D01*
X121610Y410328D01*
X121707Y410342D01*
X121846D01*
X122096Y410328D01*
D02*
G37*
G36*
X134203Y404753D02*
Y404475D01*
X134189Y404212D01*
X134175Y403962D01*
X134147Y403726D01*
X134120Y403518D01*
X134092Y403324D01*
X134050Y403144D01*
X134023Y402977D01*
X133995Y402825D01*
X133953Y402700D01*
X133926Y402589D01*
X133898Y402506D01*
X133870Y402437D01*
X133856Y402381D01*
X133842Y402353D01*
Y402340D01*
X133690Y402034D01*
X133496Y401757D01*
X133301Y401535D01*
X133093Y401341D01*
X132913Y401189D01*
X132761Y401078D01*
X132705Y401050D01*
X132663Y401022D01*
X132636Y400994D01*
X132622D01*
X132275Y400842D01*
X131915Y400731D01*
X131540Y400648D01*
X131194Y400592D01*
X131041Y400578D01*
X130888Y400564D01*
X130750Y400551D01*
X130639D01*
X130542Y400537D01*
X130417D01*
X129918Y400564D01*
X129696Y400592D01*
X129488Y400620D01*
X129280Y400662D01*
X129099Y400703D01*
X128933Y400745D01*
X128780Y400800D01*
X128642Y400856D01*
X128531Y400897D01*
X128420Y400939D01*
X128337Y400980D01*
X128267Y401022D01*
X128226Y401036D01*
X128198Y401064D01*
X128184D01*
X127879Y401272D01*
X127629Y401507D01*
X127435Y401729D01*
X127269Y401951D01*
X127144Y402145D01*
X127061Y402298D01*
X127033Y402353D01*
X127005Y402395D01*
X126991Y402423D01*
Y402437D01*
X126936Y402603D01*
X126880Y402783D01*
X126797Y403158D01*
X126742Y403546D01*
X126700Y403921D01*
X126686Y404087D01*
X126672Y404253D01*
Y404392D01*
X126658Y404517D01*
Y404614D01*
Y404683D01*
Y404739D01*
Y404753D01*
Y410300D01*
X127934D01*
Y404753D01*
Y404434D01*
X127962Y404129D01*
X127990Y403865D01*
X128032Y403615D01*
X128073Y403394D01*
X128128Y403186D01*
X128170Y403005D01*
X128226Y402853D01*
X128281Y402728D01*
X128337Y402603D01*
X128392Y402520D01*
X128434Y402437D01*
X128475Y402381D01*
X128503Y402340D01*
X128517Y402326D01*
X128531Y402312D01*
X128656Y402201D01*
X128794Y402104D01*
X129099Y401951D01*
X129418Y401840D01*
X129751Y401771D01*
X130056Y401716D01*
X130181Y401702D01*
X130306D01*
X130389Y401688D01*
X130528D01*
X130819Y401702D01*
X131082Y401743D01*
X131332Y401785D01*
X131526Y401854D01*
X131693Y401910D01*
X131818Y401951D01*
X131887Y401993D01*
X131915Y402007D01*
X132109Y402132D01*
X132275Y402284D01*
X132414Y402437D01*
X132511Y402575D01*
X132594Y402714D01*
X132663Y402811D01*
X132691Y402880D01*
X132705Y402908D01*
X132747Y403033D01*
X132774Y403158D01*
X132830Y403449D01*
X132872Y403754D01*
X132899Y404059D01*
X132913Y404323D01*
Y404448D01*
X132927Y404545D01*
Y404628D01*
Y404697D01*
Y404739D01*
Y404753D01*
Y410300D01*
X134203D01*
Y404753D01*
D02*
G37*
G36*
X136012Y363204D02*
X136276Y363176D01*
X136525Y363121D01*
X136761Y363051D01*
X136969Y362954D01*
X137177Y362871D01*
X137357Y362760D01*
X137524Y362663D01*
X137662Y362566D01*
X137801Y362455D01*
X137912Y362372D01*
X137995Y362289D01*
X138065Y362205D01*
X138120Y362150D01*
X138148Y362122D01*
X138162Y362108D01*
X138342Y361859D01*
X138495Y361567D01*
X138633Y361262D01*
X138758Y360943D01*
X138855Y360611D01*
X138938Y360278D01*
X139008Y359931D01*
X139063Y359612D01*
X139105Y359293D01*
X139132Y359002D01*
X139160Y358738D01*
X139174Y358516D01*
Y358322D01*
X139188Y358184D01*
Y358128D01*
Y358087D01*
Y358073D01*
Y358059D01*
X139174Y357615D01*
X139146Y357199D01*
X139105Y356811D01*
X139035Y356450D01*
X138966Y356131D01*
X138897Y355840D01*
X138813Y355576D01*
X138716Y355340D01*
X138633Y355146D01*
X138550Y354966D01*
X138481Y354827D01*
X138398Y354703D01*
X138342Y354605D01*
X138300Y354550D01*
X138273Y354508D01*
X138259Y354495D01*
X138078Y354300D01*
X137884Y354134D01*
X137690Y353995D01*
X137496Y353871D01*
X137288Y353759D01*
X137094Y353676D01*
X136900Y353607D01*
X136706Y353551D01*
X136539Y353510D01*
X136373Y353468D01*
X136234Y353441D01*
X136109Y353427D01*
X135998D01*
X135929Y353413D01*
X135859D01*
X135541Y353427D01*
X135249Y353482D01*
X134986Y353538D01*
X134750Y353621D01*
X134570Y353690D01*
X134431Y353759D01*
X134376Y353773D01*
X134334Y353801D01*
X134320Y353815D01*
X134306D01*
X134071Y353981D01*
X133849Y354176D01*
X133668Y354370D01*
X133516Y354564D01*
X133391Y354744D01*
X133308Y354883D01*
X133280Y354938D01*
X133252Y354980D01*
X133238Y354994D01*
Y355008D01*
X133100Y355299D01*
X133003Y355604D01*
X132933Y355881D01*
X132892Y356145D01*
X132850Y356367D01*
Y356450D01*
X132836Y356533D01*
Y356603D01*
Y356644D01*
Y356672D01*
Y356686D01*
X132850Y356935D01*
X132878Y357171D01*
X132919Y357407D01*
X132961Y357615D01*
X133030Y357809D01*
X133100Y358003D01*
X133169Y358170D01*
X133252Y358322D01*
X133336Y358461D01*
X133405Y358586D01*
X133474Y358683D01*
X133544Y358780D01*
X133585Y358849D01*
X133627Y358891D01*
X133654Y358919D01*
X133668Y358932D01*
X133821Y359085D01*
X133987Y359224D01*
X134168Y359335D01*
X134334Y359432D01*
X134500Y359529D01*
X134667Y359598D01*
X134986Y359695D01*
X135125Y359737D01*
X135263Y359765D01*
X135374Y359778D01*
X135485Y359792D01*
X135568Y359806D01*
X135679D01*
X135929Y359792D01*
X136165Y359751D01*
X136386Y359709D01*
X136581Y359654D01*
X136747Y359584D01*
X136872Y359543D01*
X136955Y359501D01*
X136969Y359487D01*
X136983D01*
X137205Y359348D01*
X137399Y359196D01*
X137579Y359043D01*
X137718Y358877D01*
X137843Y358738D01*
X137940Y358627D01*
X137995Y358544D01*
X138009Y358530D01*
Y358780D01*
X137995Y359030D01*
X137981Y359251D01*
X137954Y359473D01*
X137940Y359668D01*
X137912Y359848D01*
X137884Y360014D01*
X137843Y360167D01*
X137815Y360305D01*
X137787Y360416D01*
X137760Y360513D01*
X137746Y360597D01*
X137718Y360652D01*
X137704Y360694D01*
X137690Y360722D01*
Y360735D01*
X137551Y361013D01*
X137413Y361262D01*
X137260Y361456D01*
X137122Y361623D01*
X136997Y361762D01*
X136900Y361859D01*
X136830Y361914D01*
X136803Y361928D01*
X136636Y362039D01*
X136470Y362108D01*
X136303Y362164D01*
X136137Y362205D01*
X136012Y362233D01*
X135901Y362247D01*
X135804D01*
X135554Y362219D01*
X135319Y362164D01*
X135125Y362081D01*
X134944Y361997D01*
X134805Y361900D01*
X134708Y361817D01*
X134653Y361762D01*
X134625Y361734D01*
X134528Y361609D01*
X134431Y361456D01*
X134348Y361290D01*
X134292Y361124D01*
X134237Y360971D01*
X134195Y360846D01*
X134181Y360763D01*
X134168Y360749D01*
Y360735D01*
X132989Y360832D01*
X133072Y361221D01*
X133197Y361567D01*
X133336Y361873D01*
X133488Y362122D01*
X133641Y362316D01*
X133696Y362400D01*
X133765Y362469D01*
X133807Y362510D01*
X133849Y362552D01*
X133862Y362566D01*
X133876Y362580D01*
X134015Y362691D01*
X134168Y362788D01*
X134473Y362954D01*
X134778Y363065D01*
X135069Y363135D01*
X135332Y363190D01*
X135443Y363204D01*
X135541D01*
X135624Y363218D01*
X135735D01*
X136012Y363204D01*
D02*
G37*
G36*
X144638Y363315D02*
X145082Y363246D01*
X145470Y363162D01*
X145651Y363107D01*
X145817Y363051D01*
X145970Y362996D01*
X146108Y362940D01*
X146219Y362899D01*
X146330Y362857D01*
X146399Y362816D01*
X146455Y362788D01*
X146497Y362774D01*
X146510Y362760D01*
X146885Y362524D01*
X147204Y362247D01*
X147481Y361970D01*
X147717Y361692D01*
X147897Y361443D01*
X147967Y361332D01*
X148022Y361235D01*
X148078Y361165D01*
X148105Y361110D01*
X148119Y361068D01*
X148133Y361054D01*
X148327Y360624D01*
X148466Y360181D01*
X148563Y359737D01*
X148632Y359335D01*
X148660Y359154D01*
X148674Y358974D01*
X148688Y358835D01*
Y358697D01*
X148702Y358600D01*
Y358516D01*
Y358461D01*
Y358447D01*
X148674Y357948D01*
X148618Y357462D01*
X148549Y357033D01*
X148494Y356824D01*
X148452Y356644D01*
X148410Y356478D01*
X148355Y356325D01*
X148313Y356186D01*
X148286Y356076D01*
X148244Y355992D01*
X148230Y355923D01*
X148202Y355881D01*
Y355868D01*
X147994Y355452D01*
X147759Y355077D01*
X147509Y354758D01*
X147384Y354633D01*
X147273Y354508D01*
X147162Y354398D01*
X147051Y354300D01*
X146954Y354217D01*
X146871Y354162D01*
X146816Y354106D01*
X146760Y354065D01*
X146732Y354051D01*
X146719Y354037D01*
X146524Y353926D01*
X146330Y353829D01*
X145914Y353676D01*
X145498Y353565D01*
X145096Y353496D01*
X144902Y353468D01*
X144735Y353441D01*
X144583Y353427D01*
X144458D01*
X144347Y353413D01*
X144194D01*
X143917Y353427D01*
X143654Y353454D01*
X143404Y353482D01*
X143168Y353538D01*
X142946Y353607D01*
X142738Y353676D01*
X142544Y353746D01*
X142364Y353829D01*
X142211Y353898D01*
X142059Y353968D01*
X141948Y354037D01*
X141837Y354106D01*
X141768Y354162D01*
X141698Y354189D01*
X141670Y354217D01*
X141657Y354231D01*
X141462Y354398D01*
X141296Y354564D01*
X141143Y354758D01*
X140991Y354952D01*
X140741Y355340D01*
X140547Y355729D01*
X140464Y355909D01*
X140394Y356076D01*
X140339Y356228D01*
X140297Y356353D01*
X140256Y356464D01*
X140228Y356547D01*
X140214Y356603D01*
Y356616D01*
X141490Y356935D01*
X141546Y356713D01*
X141615Y356506D01*
X141684Y356311D01*
X141754Y356131D01*
X141837Y355965D01*
X141920Y355826D01*
X142017Y355687D01*
X142100Y355562D01*
X142170Y355452D01*
X142253Y355368D01*
X142322Y355285D01*
X142378Y355216D01*
X142433Y355174D01*
X142475Y355132D01*
X142489Y355119D01*
X142502Y355105D01*
X142641Y354994D01*
X142794Y354911D01*
X143099Y354758D01*
X143390Y354647D01*
X143681Y354578D01*
X143931Y354522D01*
X144028Y354508D01*
X144125D01*
X144208Y354495D01*
X144305D01*
X144624Y354508D01*
X144930Y354564D01*
X145207Y354633D01*
X145456Y354716D01*
X145651Y354800D01*
X145734Y354841D01*
X145803Y354869D01*
X145859Y354897D01*
X145900Y354925D01*
X145928Y354938D01*
X145942D01*
X146205Y355132D01*
X146427Y355340D01*
X146621Y355576D01*
X146774Y355798D01*
X146899Y355992D01*
X146982Y356159D01*
X147010Y356228D01*
X147037Y356270D01*
X147051Y356297D01*
Y356311D01*
X147162Y356672D01*
X147246Y357033D01*
X147315Y357393D01*
X147356Y357726D01*
X147370Y357878D01*
X147384Y358017D01*
Y358142D01*
X147398Y358239D01*
Y358322D01*
Y358392D01*
Y358433D01*
Y358447D01*
X147384Y358808D01*
X147356Y359141D01*
X147301Y359446D01*
X147246Y359723D01*
X147204Y359959D01*
X147176Y360056D01*
X147148Y360139D01*
X147135Y360208D01*
X147121Y360250D01*
X147107Y360278D01*
Y360292D01*
X146968Y360611D01*
X146816Y360902D01*
X146649Y361138D01*
X146469Y361346D01*
X146316Y361512D01*
X146192Y361623D01*
X146094Y361692D01*
X146081Y361720D01*
X146067D01*
X145775Y361900D01*
X145456Y362039D01*
X145151Y362136D01*
X144860Y362192D01*
X144597Y362233D01*
X144486Y362247D01*
X144389D01*
X144319Y362261D01*
X144208D01*
X143862Y362247D01*
X143543Y362192D01*
X143279Y362108D01*
X143043Y362025D01*
X142863Y361928D01*
X142724Y361859D01*
X142641Y361803D01*
X142613Y361776D01*
X142392Y361567D01*
X142184Y361332D01*
X142017Y361082D01*
X141878Y360832D01*
X141768Y360611D01*
X141726Y360500D01*
X141698Y360416D01*
X141670Y360347D01*
X141643Y360292D01*
X141629Y360264D01*
Y360250D01*
X140381Y360541D01*
X140464Y360791D01*
X140547Y361013D01*
X140658Y361221D01*
X140755Y361429D01*
X140866Y361609D01*
X140991Y361776D01*
X141102Y361942D01*
X141213Y362081D01*
X141324Y362192D01*
X141421Y362303D01*
X141518Y362400D01*
X141587Y362469D01*
X141657Y362538D01*
X141712Y362580D01*
X141740Y362594D01*
X141754Y362608D01*
X141948Y362732D01*
X142142Y362857D01*
X142336Y362954D01*
X142544Y363037D01*
X142960Y363162D01*
X143335Y363246D01*
X143515Y363287D01*
X143667Y363301D01*
X143820Y363315D01*
X143945Y363329D01*
X144042Y363343D01*
X144181D01*
X144638Y363315D01*
D02*
G37*
G36*
X31349Y208667D02*
X31501Y208445D01*
X31681Y208223D01*
X31848Y208029D01*
X32014Y207862D01*
X32139Y207724D01*
X32194Y207682D01*
X32236Y207640D01*
X32250Y207627D01*
X32264Y207613D01*
X32555Y207377D01*
X32846Y207155D01*
X33124Y206961D01*
X33401Y206808D01*
X33637Y206670D01*
X33734Y206614D01*
X33817Y206573D01*
X33886Y206531D01*
X33942Y206517D01*
X33970Y206489D01*
X33984D01*
Y205352D01*
X33775Y205435D01*
X33568Y205532D01*
X33359Y205630D01*
X33165Y205727D01*
X32999Y205810D01*
X32860Y205879D01*
X32777Y205935D01*
X32763Y205949D01*
X32749D01*
X32500Y206101D01*
X32278Y206254D01*
X32084Y206392D01*
X31931Y206517D01*
X31792Y206614D01*
X31709Y206697D01*
X31640Y206753D01*
X31626Y206767D01*
Y199264D01*
X30447D01*
Y208902D01*
X31210D01*
X31349Y208667D01*
D02*
G37*
G36*
X43345Y199264D02*
X42069D01*
Y203161D01*
X39614D01*
X39253Y203175D01*
X38907Y203203D01*
X38602Y203244D01*
X38324Y203300D01*
X38061Y203355D01*
X37839Y203424D01*
X37631Y203508D01*
X37451Y203591D01*
X37298Y203660D01*
X37159Y203743D01*
X37048Y203813D01*
X36965Y203882D01*
X36896Y203924D01*
X36854Y203965D01*
X36827Y203993D01*
X36813Y204007D01*
X36674Y204173D01*
X36549Y204340D01*
X36452Y204506D01*
X36355Y204687D01*
X36272Y204867D01*
X36216Y205033D01*
X36119Y205352D01*
X36091Y205505D01*
X36064Y205643D01*
X36050Y205768D01*
X36036Y205865D01*
X36022Y205962D01*
Y206018D01*
Y206059D01*
Y206073D01*
X36036Y206337D01*
X36064Y206586D01*
X36119Y206808D01*
X36161Y207003D01*
X36216Y207169D01*
X36272Y207294D01*
X36300Y207363D01*
X36313Y207391D01*
X36424Y207599D01*
X36563Y207779D01*
X36688Y207946D01*
X36813Y208070D01*
X36924Y208167D01*
X37007Y208251D01*
X37062Y208292D01*
X37090Y208306D01*
X37270Y208417D01*
X37478Y208514D01*
X37673Y208597D01*
X37853Y208667D01*
X38019Y208708D01*
X38144Y208736D01*
X38241Y208764D01*
X38269D01*
X38477Y208792D01*
X38713Y208819D01*
X38962Y208833D01*
X39198Y208847D01*
X39406Y208861D01*
X43345D01*
Y199264D01*
D02*
G37*
G36*
X24664Y208875D02*
X25011Y208819D01*
X25302Y208722D01*
X25552Y208625D01*
X25760Y208514D01*
X25843Y208473D01*
X25912Y208417D01*
X25968Y208389D01*
X26009Y208362D01*
X26023Y208334D01*
X26037D01*
X26287Y208112D01*
X26495Y207848D01*
X26675Y207585D01*
X26814Y207335D01*
X26925Y207100D01*
X26980Y207003D01*
X27008Y206905D01*
X27036Y206836D01*
X27063Y206781D01*
X27077Y206753D01*
Y206739D01*
X27133Y206531D01*
X27188Y206323D01*
X27271Y205865D01*
X27341Y205408D01*
X27382Y204978D01*
X27396Y204770D01*
X27410Y204589D01*
Y204423D01*
X27424Y204270D01*
Y204160D01*
Y204062D01*
Y204007D01*
Y203993D01*
X27410Y203508D01*
X27382Y203050D01*
X27341Y202634D01*
X27271Y202246D01*
X27202Y201885D01*
X27119Y201566D01*
X27036Y201275D01*
X26952Y201025D01*
X26869Y200803D01*
X26772Y200609D01*
X26703Y200443D01*
X26633Y200318D01*
X26564Y200207D01*
X26522Y200138D01*
X26495Y200096D01*
X26481Y200082D01*
X26328Y199916D01*
X26162Y199763D01*
X25982Y199625D01*
X25801Y199514D01*
X25621Y199417D01*
X25441Y199333D01*
X25260Y199278D01*
X25094Y199222D01*
X24927Y199181D01*
X24775Y199153D01*
X24636Y199125D01*
X24525Y199111D01*
X24428Y199097D01*
X24290D01*
X23915Y199125D01*
X23568Y199181D01*
X23277Y199278D01*
X23028Y199375D01*
X22819Y199472D01*
X22750Y199527D01*
X22681Y199569D01*
X22625Y199597D01*
X22584Y199625D01*
X22570Y199652D01*
X22556D01*
X22306Y199888D01*
X22098Y200138D01*
X21918Y200415D01*
X21779Y200665D01*
X21668Y200900D01*
X21613Y200998D01*
X21585Y201095D01*
X21558Y201164D01*
X21530Y201219D01*
X21516Y201247D01*
Y201261D01*
X21446Y201469D01*
X21391Y201677D01*
X21308Y202121D01*
X21239Y202579D01*
X21197Y203022D01*
X21183Y203216D01*
X21169Y203397D01*
Y203563D01*
X21155Y203716D01*
Y203827D01*
Y203924D01*
Y203979D01*
Y203993D01*
Y204257D01*
X21169Y204506D01*
Y204728D01*
X21183Y204950D01*
X21211Y205144D01*
X21225Y205338D01*
X21239Y205505D01*
X21266Y205657D01*
X21280Y205796D01*
X21308Y205921D01*
X21322Y206018D01*
X21336Y206101D01*
X21349Y206170D01*
X21363Y206212D01*
X21377Y206240D01*
Y206254D01*
X21460Y206559D01*
X21558Y206836D01*
X21668Y207072D01*
X21752Y207280D01*
X21849Y207460D01*
X21904Y207585D01*
X21960Y207654D01*
X21974Y207682D01*
X22126Y207890D01*
X22279Y208070D01*
X22445Y208223D01*
X22598Y208362D01*
X22736Y208459D01*
X22847Y208528D01*
X22917Y208570D01*
X22930Y208584D01*
X22944D01*
X23166Y208694D01*
X23402Y208764D01*
X23624Y208819D01*
X23832Y208861D01*
X24012Y208889D01*
X24165Y208902D01*
X24290D01*
X24664Y208875D01*
D02*
G37*
G36*
X461734Y185929D02*
X461970Y185915D01*
X462192Y185873D01*
X462400Y185832D01*
X462594Y185776D01*
X462774Y185721D01*
X462941Y185651D01*
X463093Y185582D01*
X463232Y185513D01*
X463343Y185443D01*
X463440Y185388D01*
X463523Y185333D01*
X463592Y185291D01*
X463634Y185249D01*
X463662Y185235D01*
X463676Y185222D01*
X463814Y185083D01*
X463939Y184930D01*
X464064Y184764D01*
X464161Y184597D01*
X464327Y184265D01*
X464438Y183932D01*
X464480Y183779D01*
X464521Y183627D01*
X464549Y183502D01*
X464577Y183391D01*
X464591Y183294D01*
Y183225D01*
X464605Y183183D01*
Y183169D01*
X463398Y183044D01*
X463371Y183363D01*
X463315Y183641D01*
X463232Y183890D01*
X463135Y184084D01*
X463051Y184251D01*
X462968Y184362D01*
X462913Y184431D01*
X462885Y184459D01*
X462677Y184625D01*
X462455Y184750D01*
X462219Y184847D01*
X462011Y184903D01*
X461817Y184944D01*
X461651Y184958D01*
X461595Y184972D01*
X461512D01*
X461221Y184958D01*
X460957Y184903D01*
X460736Y184819D01*
X460541Y184736D01*
X460389Y184639D01*
X460292Y184570D01*
X460222Y184514D01*
X460195Y184487D01*
X460028Y184292D01*
X459903Y184098D01*
X459806Y183904D01*
X459751Y183710D01*
X459709Y183557D01*
X459695Y183419D01*
X459682Y183335D01*
Y183322D01*
Y183308D01*
X459709Y183058D01*
X459765Y182795D01*
X459862Y182559D01*
X459959Y182337D01*
X460070Y182157D01*
X460167Y182004D01*
X460195Y181949D01*
X460222Y181907D01*
X460250Y181893D01*
Y181879D01*
X460361Y181727D01*
X460500Y181574D01*
X460652Y181408D01*
X460819Y181241D01*
X461165Y180909D01*
X461512Y180576D01*
X461692Y180423D01*
X461845Y180284D01*
X461997Y180160D01*
X462122Y180049D01*
X462219Y179965D01*
X462303Y179896D01*
X462358Y179855D01*
X462372Y179841D01*
X462719Y179549D01*
X463038Y179272D01*
X463301Y179022D01*
X463509Y178814D01*
X463689Y178634D01*
X463814Y178509D01*
X463884Y178426D01*
X463911Y178412D01*
Y178398D01*
X464105Y178162D01*
X464258Y177941D01*
X464397Y177719D01*
X464508Y177525D01*
X464591Y177358D01*
X464646Y177233D01*
X464674Y177150D01*
X464688Y177136D01*
Y177122D01*
X464743Y176970D01*
X464771Y176831D01*
X464799Y176693D01*
X464813Y176568D01*
X464827Y176457D01*
Y176374D01*
Y176318D01*
Y176304D01*
X458461D01*
Y177441D01*
X463190D01*
X463024Y177677D01*
X462941Y177774D01*
X462871Y177871D01*
X462802Y177955D01*
X462746Y178010D01*
X462705Y178052D01*
X462691Y178065D01*
X462622Y178135D01*
X462538Y178204D01*
X462344Y178384D01*
X462122Y178592D01*
X461887Y178801D01*
X461665Y178981D01*
X461568Y179064D01*
X461484Y179147D01*
X461415Y179203D01*
X461360Y179244D01*
X461332Y179272D01*
X461318Y179286D01*
X461096Y179480D01*
X460874Y179660D01*
X460680Y179841D01*
X460500Y179993D01*
X460333Y180146D01*
X460195Y180284D01*
X460056Y180409D01*
X459945Y180520D01*
X459834Y180631D01*
X459751Y180714D01*
X459682Y180784D01*
X459612Y180853D01*
X459543Y180936D01*
X459515Y180964D01*
X459321Y181200D01*
X459155Y181408D01*
X459016Y181616D01*
X458905Y181782D01*
X458822Y181935D01*
X458766Y182046D01*
X458738Y182115D01*
X458725Y182143D01*
X458641Y182351D01*
X458586Y182559D01*
X458530Y182753D01*
X458503Y182919D01*
X458489Y183072D01*
X458475Y183183D01*
Y183252D01*
Y183280D01*
X458489Y183488D01*
X458517Y183682D01*
X458544Y183876D01*
X458600Y184043D01*
X458738Y184376D01*
X458877Y184639D01*
X458960Y184764D01*
X459030Y184861D01*
X459099Y184958D01*
X459168Y185027D01*
X459224Y185083D01*
X459252Y185138D01*
X459279Y185152D01*
X459293Y185166D01*
X459446Y185305D01*
X459612Y185430D01*
X459792Y185527D01*
X459973Y185610D01*
X460333Y185749D01*
X460694Y185846D01*
X460846Y185873D01*
X460999Y185901D01*
X461138Y185915D01*
X461249Y185929D01*
X461346Y185943D01*
X461484D01*
X461734Y185929D01*
D02*
G37*
G36*
X467531Y179286D02*
Y178995D01*
X467559Y178745D01*
X467573Y178537D01*
X467600Y178371D01*
X467628Y178246D01*
X467642Y178149D01*
X467670Y178093D01*
Y178079D01*
X467725Y177941D01*
X467794Y177830D01*
X467878Y177733D01*
X467947Y177635D01*
X468030Y177580D01*
X468086Y177525D01*
X468127Y177497D01*
X468141Y177483D01*
X468280Y177414D01*
X468419Y177358D01*
X468557Y177330D01*
X468682Y177303D01*
X468807Y177289D01*
X468890Y177275D01*
X468973D01*
X469195Y177289D01*
X469403Y177344D01*
X469570Y177400D01*
X469722Y177483D01*
X469833Y177552D01*
X469916Y177622D01*
X469972Y177663D01*
X469986Y177677D01*
X470055Y177760D01*
X470111Y177857D01*
X470194Y178079D01*
X470277Y178329D01*
X470318Y178579D01*
X470360Y178814D01*
Y178911D01*
X470374Y178995D01*
X470388Y179078D01*
Y179133D01*
Y179161D01*
Y179175D01*
X471539Y179009D01*
Y178745D01*
X471525Y178509D01*
X471483Y178274D01*
X471456Y178065D01*
X471400Y177871D01*
X471345Y177705D01*
X471289Y177539D01*
X471234Y177400D01*
X471165Y177275D01*
X471109Y177164D01*
X471054Y177067D01*
X470998Y176998D01*
X470956Y176942D01*
X470929Y176887D01*
X470915Y176873D01*
X470901Y176859D01*
X470762Y176734D01*
X470624Y176623D01*
X470471Y176526D01*
X470305Y176443D01*
X469986Y176318D01*
X469681Y176235D01*
X469389Y176179D01*
X469278Y176166D01*
X469168Y176152D01*
X469084Y176138D01*
X468959D01*
X468654Y176152D01*
X468377Y176193D01*
X468127Y176249D01*
X467905Y176318D01*
X467725Y176374D01*
X467600Y176429D01*
X467517Y176471D01*
X467489Y176485D01*
X467267Y176623D01*
X467073Y176790D01*
X466921Y176956D01*
X466782Y177108D01*
X466685Y177261D01*
X466616Y177372D01*
X466574Y177455D01*
X466560Y177469D01*
Y177483D01*
X466463Y177760D01*
X466380Y178052D01*
X466324Y178371D01*
X466297Y178676D01*
X466269Y178939D01*
Y179050D01*
X466255Y179161D01*
Y179244D01*
Y179300D01*
Y179341D01*
Y179355D01*
Y185901D01*
X467531D01*
Y179286D01*
D02*
G37*
G36*
X460243Y394990D02*
X460396Y394768D01*
X460576Y394546D01*
X460742Y394352D01*
X460909Y394185D01*
X461034Y394047D01*
X461089Y394005D01*
X461131Y393963D01*
X461145Y393949D01*
X461158Y393936D01*
X461450Y393700D01*
X461741Y393478D01*
X462018Y393284D01*
X462296Y393131D01*
X462531Y392993D01*
X462629Y392937D01*
X462712Y392895D01*
X462781Y392854D01*
X462836Y392840D01*
X462864Y392812D01*
X462878D01*
Y391675D01*
X462670Y391758D01*
X462462Y391855D01*
X462254Y391952D01*
X462060Y392049D01*
X461894Y392133D01*
X461755Y392202D01*
X461672Y392257D01*
X461658Y392271D01*
X461644D01*
X461394Y392424D01*
X461172Y392576D01*
X460978Y392715D01*
X460826Y392840D01*
X460687Y392937D01*
X460604Y393020D01*
X460534Y393076D01*
X460521Y393090D01*
Y385587D01*
X459342D01*
Y395225D01*
X460104D01*
X460243Y394990D01*
D02*
G37*
G36*
X466650Y388568D02*
Y388277D01*
X466678Y388028D01*
X466692Y387820D01*
X466720Y387653D01*
X466747Y387528D01*
X466761Y387431D01*
X466789Y387376D01*
Y387362D01*
X466844Y387223D01*
X466914Y387112D01*
X466997Y387015D01*
X467066Y386918D01*
X467150Y386863D01*
X467205Y386807D01*
X467247Y386779D01*
X467261Y386766D01*
X467399Y386696D01*
X467538Y386641D01*
X467677Y386613D01*
X467801Y386585D01*
X467926Y386571D01*
X468009Y386558D01*
X468093D01*
X468315Y386571D01*
X468523Y386627D01*
X468689Y386682D01*
X468842Y386766D01*
X468952Y386835D01*
X469036Y386904D01*
X469091Y386946D01*
X469105Y386960D01*
X469174Y387043D01*
X469230Y387140D01*
X469313Y387362D01*
X469396Y387612D01*
X469438Y387861D01*
X469479Y388097D01*
Y388194D01*
X469493Y388277D01*
X469507Y388360D01*
Y388416D01*
Y388444D01*
Y388457D01*
X470658Y388291D01*
Y388028D01*
X470644Y387792D01*
X470603Y387556D01*
X470575Y387348D01*
X470520Y387154D01*
X470464Y386987D01*
X470409Y386821D01*
X470353Y386682D01*
X470284Y386558D01*
X470228Y386447D01*
X470173Y386349D01*
X470117Y386280D01*
X470076Y386225D01*
X470048Y386169D01*
X470034Y386155D01*
X470020Y386142D01*
X469882Y386017D01*
X469743Y385906D01*
X469590Y385809D01*
X469424Y385725D01*
X469105Y385601D01*
X468800Y385517D01*
X468509Y385462D01*
X468398Y385448D01*
X468287Y385434D01*
X468204Y385420D01*
X468079D01*
X467774Y385434D01*
X467496Y385476D01*
X467247Y385531D01*
X467025Y385601D01*
X466844Y385656D01*
X466720Y385712D01*
X466637Y385753D01*
X466609Y385767D01*
X466387Y385906D01*
X466193Y386072D01*
X466040Y386239D01*
X465901Y386391D01*
X465804Y386544D01*
X465735Y386655D01*
X465693Y386738D01*
X465680Y386752D01*
Y386766D01*
X465583Y387043D01*
X465499Y387334D01*
X465444Y387653D01*
X465416Y387958D01*
X465388Y388222D01*
Y388333D01*
X465374Y388444D01*
Y388527D01*
Y388582D01*
Y388624D01*
Y388638D01*
Y395184D01*
X466650D01*
Y388568D01*
D02*
G37*
G36*
X49745Y23874D02*
X48635Y23722D01*
X48538Y23874D01*
X48414Y23999D01*
X48303Y24124D01*
X48192Y24221D01*
X48081Y24290D01*
X47997Y24360D01*
X47942Y24388D01*
X47928Y24401D01*
X47748Y24485D01*
X47568Y24554D01*
X47401Y24595D01*
X47235Y24637D01*
X47096Y24651D01*
X46985Y24665D01*
X46722D01*
X46555Y24637D01*
X46264Y24568D01*
X46014Y24471D01*
X45792Y24374D01*
X45626Y24263D01*
X45501Y24166D01*
X45432Y24096D01*
X45404Y24082D01*
Y24069D01*
X45210Y23833D01*
X45071Y23583D01*
X44974Y23320D01*
X44905Y23056D01*
X44863Y22834D01*
X44849Y22737D01*
Y22654D01*
X44836Y22585D01*
Y22529D01*
Y22501D01*
Y22487D01*
Y22293D01*
X44863Y22113D01*
X44933Y21766D01*
X45030Y21475D01*
X45127Y21239D01*
X45238Y21045D01*
X45335Y20893D01*
X45376Y20851D01*
X45404Y20809D01*
X45418Y20796D01*
X45432Y20782D01*
X45543Y20671D01*
X45654Y20574D01*
X45903Y20407D01*
X46139Y20296D01*
X46375Y20227D01*
X46569Y20171D01*
X46736Y20158D01*
X46791Y20144D01*
X46874D01*
X47138Y20158D01*
X47373Y20213D01*
X47581Y20282D01*
X47748Y20366D01*
X47900Y20449D01*
X48011Y20518D01*
X48067Y20574D01*
X48095Y20587D01*
X48261Y20782D01*
X48400Y20990D01*
X48511Y21226D01*
X48594Y21433D01*
X48649Y21641D01*
X48691Y21794D01*
X48705Y21863D01*
X48719Y21905D01*
Y21933D01*
Y21947D01*
X49953Y21850D01*
X49925Y21628D01*
X49884Y21420D01*
X49759Y21031D01*
X49606Y20698D01*
X49523Y20546D01*
X49440Y20421D01*
X49370Y20296D01*
X49287Y20185D01*
X49218Y20102D01*
X49149Y20033D01*
X49093Y19977D01*
X49065Y19922D01*
X49038Y19908D01*
X49024Y19894D01*
X48857Y19769D01*
X48691Y19658D01*
X48511Y19561D01*
X48330Y19478D01*
X47984Y19353D01*
X47637Y19270D01*
X47484Y19228D01*
X47332Y19215D01*
X47207Y19201D01*
X47096Y19187D01*
X46999Y19173D01*
X46874D01*
X46583Y19187D01*
X46305Y19228D01*
X46042Y19284D01*
X45806Y19353D01*
X45584Y19450D01*
X45376Y19547D01*
X45182Y19645D01*
X45016Y19755D01*
X44863Y19866D01*
X44724Y19963D01*
X44614Y20074D01*
X44517Y20158D01*
X44447Y20227D01*
X44392Y20282D01*
X44364Y20324D01*
X44350Y20338D01*
X44211Y20518D01*
X44100Y20712D01*
X43990Y20893D01*
X43906Y21087D01*
X43768Y21461D01*
X43684Y21822D01*
X43657Y21974D01*
X43629Y22127D01*
X43615Y22252D01*
X43601Y22363D01*
X43587Y22460D01*
Y22529D01*
Y22571D01*
Y22585D01*
X43601Y22834D01*
X43629Y23070D01*
X43671Y23306D01*
X43726Y23514D01*
X43795Y23708D01*
X43865Y23902D01*
X43948Y24069D01*
X44017Y24221D01*
X44100Y24360D01*
X44184Y24485D01*
X44253Y24582D01*
X44322Y24679D01*
X44378Y24748D01*
X44419Y24790D01*
X44447Y24817D01*
X44461Y24831D01*
X44627Y24984D01*
X44794Y25122D01*
X44974Y25233D01*
X45155Y25331D01*
X45335Y25428D01*
X45515Y25497D01*
X45848Y25594D01*
X46000Y25636D01*
X46139Y25663D01*
X46264Y25677D01*
X46375Y25691D01*
X46458Y25705D01*
X46763D01*
X46930Y25677D01*
X47263Y25608D01*
X47568Y25511D01*
X47845Y25400D01*
X48067Y25289D01*
X48164Y25233D01*
X48247Y25192D01*
X48316Y25150D01*
X48358Y25122D01*
X48386Y25109D01*
X48400Y25095D01*
X47887Y27688D01*
X44045D01*
Y28812D01*
X48816D01*
X49745Y23874D01*
D02*
G37*
G36*
X58413Y19339D02*
X57137D01*
Y23236D01*
X54682D01*
X54321Y23250D01*
X53975Y23278D01*
X53670Y23320D01*
X53392Y23375D01*
X53129Y23431D01*
X52907Y23500D01*
X52699Y23583D01*
X52519Y23666D01*
X52366Y23736D01*
X52227Y23819D01*
X52116Y23888D01*
X52033Y23958D01*
X51964Y23999D01*
X51922Y24041D01*
X51894Y24069D01*
X51881Y24082D01*
X51742Y24249D01*
X51617Y24415D01*
X51520Y24582D01*
X51423Y24762D01*
X51340Y24942D01*
X51284Y25109D01*
X51187Y25428D01*
X51160Y25580D01*
X51132Y25719D01*
X51118Y25844D01*
X51104Y25941D01*
X51090Y26038D01*
Y26093D01*
Y26135D01*
Y26149D01*
X51104Y26412D01*
X51132Y26662D01*
X51187Y26884D01*
X51229Y27078D01*
X51284Y27244D01*
X51340Y27369D01*
X51368Y27438D01*
X51381Y27466D01*
X51492Y27674D01*
X51631Y27855D01*
X51756Y28021D01*
X51881Y28146D01*
X51992Y28243D01*
X52075Y28326D01*
X52130Y28368D01*
X52158Y28382D01*
X52338Y28493D01*
X52546Y28590D01*
X52741Y28673D01*
X52921Y28742D01*
X53087Y28784D01*
X53212Y28812D01*
X53309Y28839D01*
X53337D01*
X53545Y28867D01*
X53781Y28895D01*
X54030Y28909D01*
X54266Y28922D01*
X54474Y28936D01*
X58413D01*
Y19339D01*
D02*
G37*
G36*
X464357Y272850D02*
X463081D01*
Y276747D01*
X460627D01*
X460266Y276761D01*
X459919Y276789D01*
X459614Y276830D01*
X459337Y276886D01*
X459073Y276941D01*
X458851Y277010D01*
X458643Y277094D01*
X458463Y277177D01*
X458311Y277246D01*
X458172Y277329D01*
X458061Y277399D01*
X457978Y277468D01*
X457908Y277510D01*
X457867Y277551D01*
X457839Y277579D01*
X457825Y277593D01*
X457687Y277759D01*
X457562Y277926D01*
X457465Y278092D01*
X457368Y278272D01*
X457284Y278453D01*
X457229Y278619D01*
X457132Y278938D01*
X457104Y279091D01*
X457076Y279229D01*
X457062Y279354D01*
X457048Y279451D01*
X457035Y279548D01*
Y279604D01*
Y279646D01*
Y279659D01*
X457048Y279923D01*
X457076Y280173D01*
X457132Y280394D01*
X457173Y280588D01*
X457229Y280755D01*
X457284Y280880D01*
X457312Y280949D01*
X457326Y280977D01*
X457437Y281185D01*
X457575Y281365D01*
X457700Y281532D01*
X457825Y281656D01*
X457936Y281754D01*
X458019Y281837D01*
X458075Y281878D01*
X458102Y281892D01*
X458283Y282003D01*
X458491Y282100D01*
X458685Y282183D01*
X458865Y282253D01*
X459032Y282294D01*
X459156Y282322D01*
X459254Y282350D01*
X459281D01*
X459489Y282377D01*
X459725Y282405D01*
X459975Y282419D01*
X460210Y282433D01*
X460419Y282447D01*
X464357D01*
Y272850D01*
D02*
G37*
G36*
X456300Y276234D02*
Y275152D01*
X452125D01*
Y272850D01*
X450946D01*
Y275152D01*
X449643D01*
Y276234D01*
X450946D01*
Y282447D01*
X451903D01*
X456300Y276234D01*
D02*
G37*
G36*
X41048Y488639D02*
X41311Y488611D01*
X41561Y488555D01*
X41797Y488486D01*
X42005Y488389D01*
X42213Y488306D01*
X42393Y488195D01*
X42559Y488098D01*
X42698Y488001D01*
X42837Y487890D01*
X42948Y487807D01*
X43031Y487723D01*
X43100Y487640D01*
X43156Y487585D01*
X43184Y487557D01*
X43197Y487543D01*
X43378Y487293D01*
X43530Y487002D01*
X43669Y486697D01*
X43794Y486378D01*
X43891Y486045D01*
X43974Y485712D01*
X44043Y485366D01*
X44099Y485047D01*
X44141Y484728D01*
X44168Y484436D01*
X44196Y484173D01*
X44210Y483951D01*
Y483757D01*
X44224Y483618D01*
Y483563D01*
Y483521D01*
Y483507D01*
Y483493D01*
X44210Y483050D01*
X44182Y482634D01*
X44141Y482245D01*
X44071Y481885D01*
X44002Y481566D01*
X43932Y481274D01*
X43849Y481011D01*
X43752Y480775D01*
X43669Y480581D01*
X43586Y480401D01*
X43516Y480262D01*
X43433Y480137D01*
X43378Y480040D01*
X43336Y479985D01*
X43308Y479943D01*
X43295Y479929D01*
X43114Y479735D01*
X42920Y479569D01*
X42726Y479430D01*
X42532Y479305D01*
X42324Y479194D01*
X42130Y479111D01*
X41936Y479042D01*
X41741Y478986D01*
X41575Y478945D01*
X41409Y478903D01*
X41270Y478875D01*
X41145Y478861D01*
X41034D01*
X40965Y478848D01*
X40895D01*
X40576Y478861D01*
X40285Y478917D01*
X40022Y478972D01*
X39786Y479056D01*
X39606Y479125D01*
X39467Y479194D01*
X39411Y479208D01*
X39370Y479236D01*
X39356Y479250D01*
X39342D01*
X39106Y479416D01*
X38884Y479610D01*
X38704Y479804D01*
X38552Y479999D01*
X38427Y480179D01*
X38344Y480318D01*
X38316Y480373D01*
X38288Y480415D01*
X38274Y480429D01*
Y480442D01*
X38135Y480734D01*
X38038Y481039D01*
X37969Y481316D01*
X37927Y481580D01*
X37886Y481801D01*
Y481885D01*
X37872Y481968D01*
Y482037D01*
Y482079D01*
Y482107D01*
Y482121D01*
X37886Y482370D01*
X37914Y482606D01*
X37955Y482842D01*
X37997Y483050D01*
X38066Y483244D01*
X38135Y483438D01*
X38205Y483604D01*
X38288Y483757D01*
X38371Y483896D01*
X38441Y484020D01*
X38510Y484118D01*
X38579Y484215D01*
X38621Y484284D01*
X38663Y484325D01*
X38690Y484353D01*
X38704Y484367D01*
X38857Y484520D01*
X39023Y484658D01*
X39203Y484769D01*
X39370Y484866D01*
X39536Y484963D01*
X39703Y485033D01*
X40022Y485130D01*
X40160Y485172D01*
X40299Y485199D01*
X40410Y485213D01*
X40521Y485227D01*
X40604Y485241D01*
X40715D01*
X40965Y485227D01*
X41200Y485185D01*
X41422Y485144D01*
X41617Y485088D01*
X41783Y485019D01*
X41908Y484977D01*
X41991Y484936D01*
X42005Y484922D01*
X42019D01*
X42241Y484783D01*
X42435Y484631D01*
X42615Y484478D01*
X42754Y484312D01*
X42878Y484173D01*
X42976Y484062D01*
X43031Y483979D01*
X43045Y483965D01*
Y484215D01*
X43031Y484464D01*
X43017Y484686D01*
X42989Y484908D01*
X42976Y485102D01*
X42948Y485283D01*
X42920Y485449D01*
X42878Y485601D01*
X42851Y485740D01*
X42823Y485851D01*
X42795Y485948D01*
X42781Y486031D01*
X42754Y486087D01*
X42740Y486128D01*
X42726Y486156D01*
Y486170D01*
X42587Y486447D01*
X42449Y486697D01*
X42296Y486891D01*
X42157Y487058D01*
X42032Y487196D01*
X41936Y487293D01*
X41866Y487349D01*
X41838Y487363D01*
X41672Y487474D01*
X41505Y487543D01*
X41339Y487598D01*
X41173Y487640D01*
X41048Y487668D01*
X40937Y487682D01*
X40840D01*
X40590Y487654D01*
X40354Y487598D01*
X40160Y487515D01*
X39980Y487432D01*
X39841Y487335D01*
X39744Y487252D01*
X39689Y487196D01*
X39661Y487169D01*
X39564Y487044D01*
X39467Y486891D01*
X39384Y486725D01*
X39328Y486558D01*
X39273Y486406D01*
X39231Y486281D01*
X39217Y486198D01*
X39203Y486184D01*
Y486170D01*
X38025Y486267D01*
X38108Y486655D01*
X38233Y487002D01*
X38371Y487307D01*
X38524Y487557D01*
X38676Y487751D01*
X38732Y487834D01*
X38801Y487904D01*
X38843Y487945D01*
X38884Y487987D01*
X38898Y488001D01*
X38912Y488014D01*
X39051Y488125D01*
X39203Y488223D01*
X39509Y488389D01*
X39814Y488500D01*
X40105Y488569D01*
X40368Y488625D01*
X40479Y488639D01*
X40576D01*
X40660Y488652D01*
X40771D01*
X41048Y488639D01*
D02*
G37*
G36*
X52628Y479014D02*
X51352D01*
Y482911D01*
X48897D01*
X48537Y482925D01*
X48190Y482953D01*
X47885Y482994D01*
X47608Y483050D01*
X47344Y483105D01*
X47122Y483175D01*
X46914Y483258D01*
X46734Y483341D01*
X46581Y483410D01*
X46443Y483493D01*
X46332Y483563D01*
X46248Y483632D01*
X46179Y483674D01*
X46138Y483715D01*
X46110Y483743D01*
X46096Y483757D01*
X45957Y483923D01*
X45833Y484090D01*
X45735Y484256D01*
X45638Y484436D01*
X45555Y484617D01*
X45500Y484783D01*
X45403Y485102D01*
X45375Y485255D01*
X45347Y485393D01*
X45333Y485518D01*
X45319Y485615D01*
X45306Y485712D01*
Y485768D01*
Y485810D01*
Y485823D01*
X45319Y486087D01*
X45347Y486337D01*
X45403Y486558D01*
X45444Y486753D01*
X45500Y486919D01*
X45555Y487044D01*
X45583Y487113D01*
X45597Y487141D01*
X45708Y487349D01*
X45846Y487529D01*
X45971Y487696D01*
X46096Y487820D01*
X46207Y487918D01*
X46290Y488001D01*
X46346Y488042D01*
X46373Y488056D01*
X46554Y488167D01*
X46762Y488264D01*
X46956Y488347D01*
X47136Y488417D01*
X47302Y488458D01*
X47427Y488486D01*
X47524Y488514D01*
X47552D01*
X47760Y488541D01*
X47996Y488569D01*
X48246Y488583D01*
X48481Y488597D01*
X48689Y488611D01*
X52628D01*
Y479014D01*
D02*
G37*
G36*
X145315Y457371D02*
X145606Y457315D01*
X145870Y457232D01*
X146092Y457149D01*
X146272Y457066D01*
X146411Y456983D01*
X146494Y456927D01*
X146508Y456913D01*
X146522D01*
X146743Y456719D01*
X146938Y456511D01*
X147090Y456289D01*
X147229Y456081D01*
X147326Y455887D01*
X147395Y455721D01*
X147423Y455665D01*
X147437Y455624D01*
X147451Y455596D01*
Y455582D01*
X147562Y455832D01*
X147687Y456040D01*
X147811Y456220D01*
X147936Y456372D01*
X148047Y456483D01*
X148130Y456567D01*
X148186Y456622D01*
X148214Y456636D01*
X148408Y456761D01*
X148602Y456844D01*
X148796Y456913D01*
X148990Y456955D01*
X149143Y456983D01*
X149268Y456997D01*
X149351D01*
X149365D01*
X149378D01*
X149573Y456983D01*
X149753Y456969D01*
X150100Y456872D01*
X150405Y456747D01*
X150668Y456608D01*
X150876Y456470D01*
X150960Y456400D01*
X151043Y456345D01*
X151098Y456289D01*
X151140Y456248D01*
X151154Y456234D01*
X151167Y456220D01*
X151292Y456067D01*
X151417Y455915D01*
X151514Y455748D01*
X151597Y455582D01*
X151722Y455249D01*
X151805Y454916D01*
X151847Y454778D01*
X151861Y454639D01*
X151875Y454514D01*
X151889Y454403D01*
X151903Y454320D01*
Y454195D01*
X151889Y453973D01*
X151875Y453751D01*
X151792Y453363D01*
X151736Y453183D01*
X151681Y453016D01*
X151611Y452864D01*
X151542Y452725D01*
X151473Y452614D01*
X151403Y452503D01*
X151348Y452406D01*
X151292Y452337D01*
X151251Y452281D01*
X151209Y452240D01*
X151195Y452212D01*
X151181Y452198D01*
X151043Y452073D01*
X150904Y451949D01*
X150751Y451851D01*
X150599Y451768D01*
X150308Y451629D01*
X150030Y451546D01*
X149795Y451491D01*
X149684Y451477D01*
X149600Y451463D01*
X149517Y451449D01*
X149462D01*
X149434D01*
X149420D01*
X149170Y451463D01*
X148935Y451505D01*
X148727Y451560D01*
X148546Y451629D01*
X148408Y451685D01*
X148297Y451740D01*
X148241Y451782D01*
X148214Y451796D01*
X148047Y451949D01*
X147894Y452115D01*
X147756Y452295D01*
X147645Y452476D01*
X147562Y452642D01*
X147506Y452767D01*
X147479Y452822D01*
X147465Y452864D01*
X147451Y452878D01*
Y452892D01*
X147354Y452573D01*
X147229Y452309D01*
X147076Y452073D01*
X146938Y451879D01*
X146799Y451727D01*
X146688Y451616D01*
X146619Y451560D01*
X146605Y451532D01*
X146591D01*
X146341Y451380D01*
X146078Y451255D01*
X145828Y451172D01*
X145578Y451116D01*
X145357Y451089D01*
X145260Y451075D01*
X145176D01*
X145121Y451061D01*
X145065D01*
X145038D01*
X145024D01*
X144802Y451075D01*
X144580Y451102D01*
X144372Y451144D01*
X144164Y451200D01*
X143817Y451338D01*
X143651Y451408D01*
X143512Y451491D01*
X143373Y451574D01*
X143263Y451643D01*
X143165Y451727D01*
X143082Y451782D01*
X143013Y451838D01*
X142971Y451879D01*
X142943Y451907D01*
X142930Y451921D01*
X142777Y452087D01*
X142652Y452267D01*
X142541Y452462D01*
X142444Y452656D01*
X142375Y452836D01*
X142306Y453030D01*
X142208Y453405D01*
X142167Y453571D01*
X142139Y453724D01*
X142125Y453862D01*
X142111Y453987D01*
X142098Y454084D01*
Y454223D01*
X142111Y454486D01*
X142139Y454722D01*
X142181Y454958D01*
X142222Y455180D01*
X142292Y455374D01*
X142361Y455568D01*
X142430Y455748D01*
X142514Y455901D01*
X142597Y456040D01*
X142666Y456165D01*
X142736Y456261D01*
X142805Y456359D01*
X142846Y456428D01*
X142888Y456470D01*
X142916Y456497D01*
X142930Y456511D01*
X143096Y456664D01*
X143263Y456802D01*
X143429Y456913D01*
X143609Y457010D01*
X143776Y457108D01*
X143956Y457177D01*
X144275Y457274D01*
X144427Y457315D01*
X144566Y457343D01*
X144691Y457357D01*
X144788Y457371D01*
X144871Y457385D01*
X144941D01*
X144982D01*
X144996D01*
X145315Y457371D01*
D02*
G37*
G36*
X149337Y449924D02*
X149586Y449896D01*
X149808Y449841D01*
X150002Y449799D01*
X150169Y449743D01*
X150294Y449688D01*
X150363Y449660D01*
X150391Y449646D01*
X150599Y449535D01*
X150779Y449397D01*
X150946Y449272D01*
X151070Y449147D01*
X151167Y449036D01*
X151251Y448953D01*
X151292Y448897D01*
X151306Y448870D01*
X151417Y448689D01*
X151514Y448481D01*
X151597Y448287D01*
X151667Y448107D01*
X151708Y447940D01*
X151736Y447816D01*
X151764Y447719D01*
Y447691D01*
X151792Y447483D01*
X151819Y447247D01*
X151833Y446997D01*
X151847Y446762D01*
X151861Y446554D01*
Y442615D01*
X142264D01*
Y443891D01*
X146161D01*
Y446346D01*
X146175Y446706D01*
X146203Y447053D01*
X146244Y447358D01*
X146300Y447635D01*
X146355Y447899D01*
X146425Y448121D01*
X146508Y448329D01*
X146591Y448509D01*
X146660Y448662D01*
X146743Y448800D01*
X146813Y448911D01*
X146882Y448994D01*
X146924Y449064D01*
X146965Y449105D01*
X146993Y449133D01*
X147007Y449147D01*
X147173Y449286D01*
X147340Y449411D01*
X147506Y449508D01*
X147687Y449605D01*
X147867Y449688D01*
X148033Y449743D01*
X148352Y449841D01*
X148505Y449868D01*
X148643Y449896D01*
X148768Y449910D01*
X148865Y449924D01*
X148962Y449938D01*
X149018D01*
X149059D01*
X149073D01*
X149337Y449924D01*
D02*
G37*
G36*
X163924Y451165D02*
X162786D01*
Y455866D01*
X162384Y455533D01*
X161954Y455215D01*
X161538Y454937D01*
X161136Y454674D01*
X160956Y454563D01*
X160789Y454466D01*
X160637Y454369D01*
X160512Y454299D01*
X160401Y454244D01*
X160332Y454202D01*
X160276Y454174D01*
X160262Y454160D01*
X159708Y453883D01*
X159153Y453633D01*
X158626Y453425D01*
X158390Y453342D01*
X158154Y453259D01*
X157946Y453176D01*
X157752Y453120D01*
X157586Y453065D01*
X157447Y453023D01*
X157322Y452982D01*
X157239Y452954D01*
X157184Y452940D01*
X157170D01*
X156601Y452801D01*
X156324Y452746D01*
X156074Y452704D01*
X155838Y452663D01*
X155603Y452621D01*
X155408Y452593D01*
X155214Y452566D01*
X155048Y452552D01*
X154895Y452538D01*
X154757Y452524D01*
X154646D01*
X154563Y452510D01*
X154507D01*
X154465D01*
X154452D01*
Y453717D01*
X154979Y453758D01*
X155464Y453828D01*
X155908Y453897D01*
X156116Y453939D01*
X156310Y453980D01*
X156476Y454008D01*
X156629Y454049D01*
X156768Y454077D01*
X156878Y454105D01*
X156962Y454133D01*
X157031Y454147D01*
X157073Y454160D01*
X157086D01*
X157725Y454369D01*
X158321Y454590D01*
X158612Y454701D01*
X158889Y454812D01*
X159139Y454937D01*
X159389Y455048D01*
X159611Y455145D01*
X159805Y455242D01*
X159971Y455325D01*
X160124Y455395D01*
X160249Y455464D01*
X160332Y455506D01*
X160387Y455533D01*
X160401Y455547D01*
X160692Y455714D01*
X160984Y455880D01*
X161247Y456047D01*
X161497Y456213D01*
X161719Y456366D01*
X161940Y456518D01*
X162135Y456671D01*
X162301Y456796D01*
X162467Y456920D01*
X162606Y457031D01*
X162717Y457142D01*
X162814Y457225D01*
X162897Y457281D01*
X162953Y457336D01*
X162981Y457364D01*
X162994Y457378D01*
X163924D01*
Y451165D01*
D02*
G37*
G36*
X161524Y449931D02*
X161774Y449903D01*
X161996Y449847D01*
X162190Y449806D01*
X162356Y449750D01*
X162481Y449695D01*
X162551Y449667D01*
X162578Y449653D01*
X162786Y449542D01*
X162967Y449404D01*
X163133Y449279D01*
X163258Y449154D01*
X163355Y449043D01*
X163438Y448960D01*
X163480Y448904D01*
X163494Y448877D01*
X163605Y448696D01*
X163702Y448488D01*
X163785Y448294D01*
X163854Y448114D01*
X163896Y447947D01*
X163924Y447823D01*
X163951Y447725D01*
Y447698D01*
X163979Y447490D01*
X164007Y447254D01*
X164021Y447004D01*
X164035Y446769D01*
X164049Y446561D01*
Y442622D01*
X154452D01*
Y443898D01*
X158349D01*
Y446353D01*
X158362Y446713D01*
X158390Y447060D01*
X158432Y447365D01*
X158487Y447642D01*
X158543Y447906D01*
X158612Y448128D01*
X158695Y448336D01*
X158778Y448516D01*
X158848Y448669D01*
X158931Y448807D01*
X159000Y448918D01*
X159070Y449001D01*
X159111Y449071D01*
X159153Y449112D01*
X159181Y449140D01*
X159194Y449154D01*
X159361Y449293D01*
X159527Y449417D01*
X159694Y449515D01*
X159874Y449612D01*
X160054Y449695D01*
X160221Y449750D01*
X160540Y449847D01*
X160692Y449875D01*
X160831Y449903D01*
X160956Y449917D01*
X161053Y449931D01*
X161150Y449944D01*
X161205D01*
X161247D01*
X161261D01*
X161524Y449931D01*
D02*
G37*
G36*
X453311Y485631D02*
X453685Y485562D01*
X454004Y485451D01*
X454282Y485340D01*
X454407Y485271D01*
X454504Y485215D01*
X454601Y485160D01*
X454670Y485104D01*
X454726Y485063D01*
X454767Y485035D01*
X454795Y485021D01*
X454809Y485007D01*
X455072Y484744D01*
X455280Y484452D01*
X455447Y484147D01*
X455585Y483842D01*
X455669Y483579D01*
X455710Y483468D01*
X455738Y483371D01*
X455752Y483288D01*
X455766Y483232D01*
X455780Y483190D01*
Y483176D01*
X454601Y482968D01*
X454545Y483274D01*
X454462Y483537D01*
X454365Y483759D01*
X454268Y483939D01*
X454171Y484078D01*
X454088Y484175D01*
X454032Y484244D01*
X454018Y484258D01*
X453838Y484397D01*
X453644Y484508D01*
X453464Y484577D01*
X453283Y484633D01*
X453117Y484660D01*
X452992Y484688D01*
X452881D01*
X452631Y484674D01*
X452410Y484619D01*
X452215Y484549D01*
X452049Y484480D01*
X451924Y484397D01*
X451827Y484328D01*
X451758Y484272D01*
X451744Y484258D01*
X451591Y484092D01*
X451480Y483912D01*
X451411Y483731D01*
X451356Y483565D01*
X451328Y483412D01*
X451300Y483301D01*
Y483218D01*
Y483204D01*
Y483190D01*
Y483038D01*
X451328Y482899D01*
X451397Y482663D01*
X451494Y482455D01*
X451605Y482275D01*
X451716Y482150D01*
X451813Y482053D01*
X451883Y481998D01*
X451896Y481984D01*
X451910D01*
X452146Y481859D01*
X452368Y481762D01*
X452604Y481693D01*
X452812Y481651D01*
X452992Y481623D01*
X453145Y481595D01*
X453325D01*
X453380Y481609D01*
X453450D01*
X453588Y480569D01*
X453408Y480611D01*
X453242Y480639D01*
X453103Y480666D01*
X452978Y480680D01*
X452881Y480694D01*
X452756D01*
X452465Y480666D01*
X452201Y480611D01*
X451966Y480528D01*
X451772Y480431D01*
X451619Y480334D01*
X451508Y480250D01*
X451439Y480195D01*
X451411Y480167D01*
X451231Y479959D01*
X451092Y479737D01*
X450995Y479515D01*
X450939Y479293D01*
X450898Y479113D01*
X450884Y478960D01*
X450870Y478905D01*
Y478863D01*
Y478836D01*
Y478822D01*
X450898Y478517D01*
X450967Y478239D01*
X451050Y478004D01*
X451161Y477796D01*
X451272Y477629D01*
X451356Y477504D01*
X451425Y477421D01*
X451453Y477393D01*
X451674Y477199D01*
X451910Y477061D01*
X452146Y476964D01*
X452368Y476894D01*
X452562Y476852D01*
X452715Y476839D01*
X452770Y476825D01*
X452853D01*
X453103Y476839D01*
X453339Y476894D01*
X453547Y476964D01*
X453713Y477047D01*
X453852Y477116D01*
X453963Y477185D01*
X454018Y477241D01*
X454046Y477255D01*
X454212Y477449D01*
X454351Y477671D01*
X454476Y477906D01*
X454573Y478156D01*
X454642Y478364D01*
X454670Y478461D01*
X454684Y478545D01*
X454698Y478614D01*
X454712Y478669D01*
X454726Y478697D01*
Y478711D01*
X455904Y478558D01*
X455877Y478336D01*
X455835Y478128D01*
X455710Y477740D01*
X455558Y477407D01*
X455475Y477269D01*
X455391Y477130D01*
X455308Y477005D01*
X455225Y476908D01*
X455155Y476811D01*
X455086Y476742D01*
X455045Y476686D01*
X455003Y476645D01*
X454975Y476617D01*
X454961Y476603D01*
X454795Y476478D01*
X454628Y476353D01*
X454462Y476256D01*
X454282Y476173D01*
X453935Y476034D01*
X453602Y475951D01*
X453450Y475923D01*
X453311Y475896D01*
X453186Y475882D01*
X453075Y475868D01*
X452992Y475854D01*
X452867D01*
X452604Y475868D01*
X452368Y475896D01*
X452132Y475937D01*
X451910Y475993D01*
X451702Y476062D01*
X451522Y476131D01*
X451342Y476215D01*
X451189Y476298D01*
X451037Y476367D01*
X450912Y476450D01*
X450801Y476520D01*
X450718Y476589D01*
X450648Y476645D01*
X450593Y476686D01*
X450565Y476714D01*
X450551Y476728D01*
X450385Y476894D01*
X450246Y477074D01*
X450121Y477255D01*
X450010Y477435D01*
X449927Y477601D01*
X449844Y477782D01*
X449733Y478115D01*
X449705Y478267D01*
X449678Y478406D01*
X449650Y478531D01*
X449636Y478642D01*
X449622Y478725D01*
Y478794D01*
Y478836D01*
Y478850D01*
X449636Y479182D01*
X449691Y479487D01*
X449775Y479751D01*
X449858Y479973D01*
X449941Y480153D01*
X450024Y480292D01*
X450080Y480375D01*
X450093Y480403D01*
X450288Y480611D01*
X450496Y480791D01*
X450718Y480930D01*
X450939Y481041D01*
X451134Y481124D01*
X451286Y481180D01*
X451342Y481193D01*
X451383Y481207D01*
X451411Y481221D01*
X451425D01*
X451189Y481346D01*
X450995Y481471D01*
X450829Y481609D01*
X450690Y481734D01*
X450579Y481845D01*
X450496Y481942D01*
X450454Y481998D01*
X450440Y482025D01*
X450329Y482220D01*
X450246Y482414D01*
X450177Y482608D01*
X450135Y482788D01*
X450107Y482941D01*
X450093Y483052D01*
Y483135D01*
Y483163D01*
X450107Y483398D01*
X450149Y483634D01*
X450205Y483842D01*
X450274Y484022D01*
X450343Y484175D01*
X450399Y484300D01*
X450440Y484369D01*
X450454Y484397D01*
X450593Y484605D01*
X450759Y484785D01*
X450926Y484938D01*
X451092Y485076D01*
X451231Y485174D01*
X451356Y485257D01*
X451439Y485298D01*
X451453Y485312D01*
X451466D01*
X451716Y485423D01*
X451966Y485506D01*
X452215Y485576D01*
X452437Y485617D01*
X452618Y485645D01*
X452770Y485659D01*
X453117D01*
X453311Y485631D01*
D02*
G37*
G36*
X464378Y476020D02*
X463102D01*
Y479917D01*
X460647D01*
X460287Y479931D01*
X459940Y479959D01*
X459635Y480001D01*
X459358Y480056D01*
X459094Y480112D01*
X458872Y480181D01*
X458664Y480264D01*
X458484Y480347D01*
X458331Y480417D01*
X458193Y480500D01*
X458082Y480569D01*
X457999Y480639D01*
X457929Y480680D01*
X457888Y480722D01*
X457860Y480750D01*
X457846Y480763D01*
X457707Y480930D01*
X457583Y481096D01*
X457485Y481263D01*
X457388Y481443D01*
X457305Y481623D01*
X457250Y481790D01*
X457153Y482109D01*
X457125Y482261D01*
X457097Y482400D01*
X457083Y482525D01*
X457069Y482622D01*
X457056Y482719D01*
Y482774D01*
Y482816D01*
Y482830D01*
X457069Y483093D01*
X457097Y483343D01*
X457153Y483565D01*
X457194Y483759D01*
X457250Y483925D01*
X457305Y484050D01*
X457333Y484120D01*
X457347Y484147D01*
X457458Y484355D01*
X457596Y484536D01*
X457721Y484702D01*
X457846Y484827D01*
X457957Y484924D01*
X458040Y485007D01*
X458096Y485049D01*
X458123Y485063D01*
X458304Y485174D01*
X458512Y485271D01*
X458706Y485354D01*
X458886Y485423D01*
X459053Y485465D01*
X459177Y485493D01*
X459274Y485520D01*
X459302D01*
X459510Y485548D01*
X459746Y485576D01*
X459996Y485590D01*
X460231Y485603D01*
X460439Y485617D01*
X464378D01*
Y476020D01*
D02*
G37*
G36*
X451453Y30843D02*
X451605Y30621D01*
X451786Y30399D01*
X451952Y30205D01*
X452118Y30039D01*
X452243Y29900D01*
X452299Y29858D01*
X452340Y29817D01*
X452354Y29803D01*
X452368Y29789D01*
X452659Y29553D01*
X452950Y29331D01*
X453228Y29137D01*
X453505Y28985D01*
X453741Y28846D01*
X453838Y28791D01*
X453921Y28749D01*
X453991Y28707D01*
X454046Y28693D01*
X454074Y28666D01*
X454088D01*
Y27529D01*
X453880Y27612D01*
X453672Y27709D01*
X453464Y27806D01*
X453269Y27903D01*
X453103Y27986D01*
X452964Y28056D01*
X452881Y28111D01*
X452867Y28125D01*
X452853D01*
X452604Y28277D01*
X452382Y28430D01*
X452188Y28569D01*
X452035Y28693D01*
X451896Y28791D01*
X451813Y28874D01*
X451744Y28929D01*
X451730Y28943D01*
Y21440D01*
X450551D01*
Y31079D01*
X451314D01*
X451453Y30843D01*
D02*
G37*
G36*
X463449Y21440D02*
X462173D01*
Y25337D01*
X459718D01*
X459358Y25351D01*
X459011Y25379D01*
X458706Y25420D01*
X458428Y25476D01*
X458165Y25531D01*
X457943Y25601D01*
X457735Y25684D01*
X457555Y25767D01*
X457402Y25837D01*
X457263Y25920D01*
X457153Y25989D01*
X457069Y26058D01*
X457000Y26100D01*
X456958Y26142D01*
X456931Y26169D01*
X456917Y26183D01*
X456778Y26350D01*
X456653Y26516D01*
X456556Y26683D01*
X456459Y26863D01*
X456376Y27043D01*
X456320Y27209D01*
X456223Y27529D01*
X456196Y27681D01*
X456168Y27820D01*
X456154Y27945D01*
X456140Y28042D01*
X456126Y28139D01*
Y28194D01*
Y28236D01*
Y28250D01*
X456140Y28513D01*
X456168Y28763D01*
X456223Y28985D01*
X456265Y29179D01*
X456320Y29345D01*
X456376Y29470D01*
X456404Y29539D01*
X456418Y29567D01*
X456529Y29775D01*
X456667Y29955D01*
X456792Y30122D01*
X456917Y30247D01*
X457028Y30344D01*
X457111Y30427D01*
X457166Y30469D01*
X457194Y30482D01*
X457374Y30593D01*
X457583Y30691D01*
X457777Y30774D01*
X457957Y30843D01*
X458123Y30885D01*
X458248Y30912D01*
X458345Y30940D01*
X458373D01*
X458581Y30968D01*
X458817Y30996D01*
X459066Y31010D01*
X459302Y31023D01*
X459510Y31037D01*
X463449D01*
Y21440D01*
D02*
G37*
G36*
X21693Y461805D02*
X21929Y461791D01*
X22151Y461750D01*
X22359Y461708D01*
X22553Y461653D01*
X22734Y461597D01*
X22900Y461528D01*
X23053Y461459D01*
X23191Y461389D01*
X23302Y461320D01*
X23399Y461264D01*
X23482Y461209D01*
X23552Y461167D01*
X23593Y461126D01*
X23621Y461112D01*
X23635Y461098D01*
X23774Y460959D01*
X23899Y460807D01*
X24023Y460640D01*
X24121Y460474D01*
X24287Y460141D01*
X24398Y459808D01*
X24439Y459656D01*
X24481Y459503D01*
X24509Y459378D01*
X24536Y459268D01*
X24550Y459170D01*
Y459101D01*
X24564Y459059D01*
Y459046D01*
X23358Y458921D01*
X23330Y459240D01*
X23275Y459517D01*
X23191Y459767D01*
X23094Y459961D01*
X23011Y460127D01*
X22928Y460238D01*
X22872Y460308D01*
X22845Y460335D01*
X22637Y460502D01*
X22415Y460627D01*
X22179Y460724D01*
X21971Y460779D01*
X21777Y460821D01*
X21610Y460835D01*
X21555Y460849D01*
X21472D01*
X21180Y460835D01*
X20917Y460779D01*
X20695Y460696D01*
X20501Y460613D01*
X20348Y460516D01*
X20251Y460446D01*
X20182Y460391D01*
X20154Y460363D01*
X19988Y460169D01*
X19863Y459975D01*
X19766Y459781D01*
X19710Y459586D01*
X19669Y459434D01*
X19655Y459295D01*
X19641Y459212D01*
Y459198D01*
Y459184D01*
X19669Y458935D01*
X19724Y458671D01*
X19821Y458435D01*
X19918Y458214D01*
X20029Y458033D01*
X20126Y457881D01*
X20154Y457825D01*
X20182Y457784D01*
X20210Y457770D01*
Y457756D01*
X20320Y457603D01*
X20459Y457451D01*
X20612Y457284D01*
X20778Y457118D01*
X21125Y456785D01*
X21472Y456452D01*
X21652Y456300D01*
X21804Y456161D01*
X21957Y456036D01*
X22082Y455925D01*
X22179Y455842D01*
X22262Y455773D01*
X22318Y455731D01*
X22332Y455717D01*
X22678Y455426D01*
X22997Y455149D01*
X23261Y454899D01*
X23469Y454691D01*
X23649Y454511D01*
X23774Y454386D01*
X23843Y454303D01*
X23871Y454289D01*
Y454275D01*
X24065Y454039D01*
X24218Y453817D01*
X24356Y453595D01*
X24467Y453401D01*
X24550Y453235D01*
X24606Y453110D01*
X24634Y453027D01*
X24648Y453013D01*
Y452999D01*
X24703Y452846D01*
X24731Y452708D01*
X24758Y452569D01*
X24772Y452444D01*
X24786Y452333D01*
Y452250D01*
Y452195D01*
Y452181D01*
X18421D01*
Y453318D01*
X23150D01*
X22983Y453554D01*
X22900Y453651D01*
X22831Y453748D01*
X22761Y453831D01*
X22706Y453886D01*
X22664Y453928D01*
X22650Y453942D01*
X22581Y454011D01*
X22498Y454081D01*
X22304Y454261D01*
X22082Y454469D01*
X21846Y454677D01*
X21624Y454857D01*
X21527Y454940D01*
X21444Y455024D01*
X21374Y455079D01*
X21319Y455121D01*
X21291Y455149D01*
X21277Y455162D01*
X21056Y455357D01*
X20834Y455537D01*
X20640Y455717D01*
X20459Y455870D01*
X20293Y456022D01*
X20154Y456161D01*
X20015Y456286D01*
X19905Y456397D01*
X19793Y456508D01*
X19710Y456591D01*
X19641Y456660D01*
X19572Y456730D01*
X19502Y456813D01*
X19475Y456841D01*
X19280Y457076D01*
X19114Y457284D01*
X18975Y457492D01*
X18864Y457659D01*
X18781Y457811D01*
X18726Y457922D01*
X18698Y457992D01*
X18684Y458019D01*
X18601Y458227D01*
X18545Y458435D01*
X18490Y458629D01*
X18462Y458796D01*
X18448Y458949D01*
X18434Y459059D01*
Y459129D01*
Y459156D01*
X18448Y459365D01*
X18476Y459559D01*
X18504Y459753D01*
X18559Y459919D01*
X18698Y460252D01*
X18837Y460516D01*
X18920Y460640D01*
X18989Y460737D01*
X19059Y460835D01*
X19128Y460904D01*
X19183Y460959D01*
X19211Y461015D01*
X19239Y461029D01*
X19253Y461043D01*
X19405Y461181D01*
X19572Y461306D01*
X19752Y461403D01*
X19932Y461486D01*
X20293Y461625D01*
X20653Y461722D01*
X20806Y461750D01*
X20958Y461778D01*
X21097Y461791D01*
X21208Y461805D01*
X21305Y461819D01*
X21444D01*
X21693Y461805D01*
D02*
G37*
G36*
X33080Y452181D02*
X31804D01*
Y456078D01*
X29349D01*
X28988Y456092D01*
X28642Y456119D01*
X28337Y456161D01*
X28059Y456216D01*
X27796Y456272D01*
X27574Y456341D01*
X27366Y456424D01*
X27185Y456508D01*
X27033Y456577D01*
X26894Y456660D01*
X26783Y456730D01*
X26700Y456799D01*
X26631Y456841D01*
X26589Y456882D01*
X26561Y456910D01*
X26547Y456924D01*
X26409Y457090D01*
X26284Y457257D01*
X26187Y457423D01*
X26090Y457603D01*
X26007Y457784D01*
X25951Y457950D01*
X25854Y458269D01*
X25826Y458422D01*
X25799Y458560D01*
X25785Y458685D01*
X25771Y458782D01*
X25757Y458879D01*
Y458935D01*
Y458976D01*
Y458990D01*
X25771Y459254D01*
X25799Y459503D01*
X25854Y459725D01*
X25896Y459919D01*
X25951Y460086D01*
X26007Y460210D01*
X26034Y460280D01*
X26048Y460308D01*
X26159Y460516D01*
X26298Y460696D01*
X26423Y460862D01*
X26547Y460987D01*
X26658Y461084D01*
X26742Y461167D01*
X26797Y461209D01*
X26825Y461223D01*
X27005Y461334D01*
X27213Y461431D01*
X27407Y461514D01*
X27588Y461584D01*
X27754Y461625D01*
X27879Y461653D01*
X27976Y461681D01*
X28004D01*
X28212Y461708D01*
X28447Y461736D01*
X28697Y461750D01*
X28933Y461764D01*
X29141Y461778D01*
X33080D01*
Y452181D01*
D02*
G37*
%LPC*%
G36*
X34531Y291342D02*
X34484D01*
X34461D01*
X34449D01*
X34144Y291318D01*
X33874Y291271D01*
X33651Y291201D01*
X33463Y291119D01*
X33311Y291025D01*
X33205Y290955D01*
X33135Y290908D01*
X33112Y290884D01*
X32947Y290708D01*
X32830Y290520D01*
X32748Y290333D01*
X32689Y290145D01*
X32654Y289992D01*
X32642Y289863D01*
X32630Y289816D01*
Y289746D01*
X32654Y289499D01*
X32701Y289277D01*
X32783Y289077D01*
X32877Y288901D01*
X32959Y288772D01*
X33041Y288666D01*
X33088Y288608D01*
X33112Y288584D01*
X33299Y288432D01*
X33510Y288314D01*
X33722Y288244D01*
X33921Y288185D01*
X34097Y288150D01*
X34168Y288138D01*
X34238D01*
X34297Y288127D01*
X34332D01*
X34355D01*
X34367D01*
X34672Y288150D01*
X34954Y288197D01*
X35200Y288279D01*
X35400Y288373D01*
X35564Y288455D01*
X35681Y288537D01*
X35717Y288561D01*
X35752Y288584D01*
X35763Y288608D01*
X35775D01*
X35869Y288701D01*
X35963Y288795D01*
X36092Y288995D01*
X36198Y289194D01*
X36256Y289382D01*
X36303Y289535D01*
X36315Y289664D01*
X36327Y289711D01*
Y289898D01*
X36303Y290016D01*
X36245Y290227D01*
X36163Y290415D01*
X36080Y290579D01*
X35986Y290708D01*
X35904Y290802D01*
X35846Y290861D01*
X35834Y290884D01*
X35822D01*
X35623Y291037D01*
X35400Y291154D01*
X35165Y291236D01*
X34942Y291283D01*
X34754Y291318D01*
X34672Y291330D01*
X34590D01*
X34531Y291342D01*
D02*
G37*
G36*
X75182Y291858D02*
X75076D01*
X75018D01*
X75006D01*
X74994D01*
X74630D01*
X74302Y291835D01*
X74008Y291811D01*
X73727Y291788D01*
X73492Y291753D01*
X73269Y291706D01*
X73081Y291659D01*
X72905Y291623D01*
X72765Y291577D01*
X72647Y291530D01*
X72542Y291494D01*
X72459Y291448D01*
X72401Y291424D01*
X72365Y291401D01*
X72342Y291377D01*
X72330D01*
X72213Y291283D01*
X72119Y291189D01*
X72025Y291095D01*
X71955Y291002D01*
X71838Y290802D01*
X71755Y290626D01*
X71708Y290462D01*
X71685Y290344D01*
X71673Y290298D01*
Y290227D01*
X71685Y290098D01*
X71697Y289981D01*
X71779Y289758D01*
X71884Y289558D01*
X72002Y289382D01*
X72119Y289253D01*
X72225Y289147D01*
X72307Y289089D01*
X72319Y289065D01*
X72330D01*
X72471Y288983D01*
X72635Y288913D01*
X72823Y288842D01*
X73023Y288795D01*
X73234Y288748D01*
X73457Y288713D01*
X73914Y288655D01*
X74126Y288631D01*
X74325Y288619D01*
X74513Y288608D01*
X74666D01*
X74806Y288596D01*
X74912D01*
X74971D01*
X74994D01*
X75358Y288608D01*
X75686Y288619D01*
X75992Y288643D01*
X76273Y288678D01*
X76520Y288713D01*
X76743Y288760D01*
X76942Y288807D01*
X77118Y288854D01*
X77271Y288901D01*
X77400Y288936D01*
X77505Y288983D01*
X77599Y289018D01*
X77658Y289054D01*
X77705Y289077D01*
X77728Y289100D01*
X77740D01*
X77846Y289183D01*
X77940Y289265D01*
X78010Y289359D01*
X78080Y289453D01*
X78186Y289640D01*
X78256Y289816D01*
X78292Y289969D01*
X78315Y290098D01*
X78327Y290145D01*
Y290215D01*
X78315Y290344D01*
X78303Y290473D01*
X78268Y290591D01*
X78221Y290696D01*
X78116Y290896D01*
X77998Y291072D01*
X77869Y291201D01*
X77764Y291307D01*
X77717Y291342D01*
X77681Y291365D01*
X77670Y291389D01*
X77658D01*
X77517Y291471D01*
X77353Y291541D01*
X77165Y291612D01*
X76966Y291659D01*
X76754Y291706D01*
X76531Y291741D01*
X76086Y291800D01*
X75862Y291823D01*
X75663Y291835D01*
X75475Y291847D01*
X75323D01*
X75182Y291858D01*
D02*
G37*
G36*
X117645Y124295D02*
X114899D01*
X114649Y124281D01*
X114441Y124267D01*
X114275Y124253D01*
X114164Y124226D01*
X114081Y124212D01*
X114025Y124198D01*
X114011D01*
X113831Y124129D01*
X113679Y124045D01*
X113540Y123962D01*
X113415Y123865D01*
X113332Y123768D01*
X113263Y123699D01*
X113221Y123643D01*
X113207Y123629D01*
X113110Y123463D01*
X113027Y123296D01*
X112971Y123116D01*
X112944Y122964D01*
X112916Y122825D01*
X112902Y122700D01*
Y122631D01*
Y122617D01*
Y122603D01*
X112930Y122312D01*
X112985Y122062D01*
X113068Y121840D01*
X113166Y121660D01*
X113263Y121521D01*
X113346Y121410D01*
X113401Y121355D01*
X113429Y121327D01*
X113526Y121244D01*
X113651Y121175D01*
X113914Y121064D01*
X114206Y120981D01*
X114497Y120925D01*
X114760Y120897D01*
X114871Y120883D01*
X114968D01*
X115065Y120870D01*
X117645D01*
Y124295D01*
D02*
G37*
G36*
X99228Y123518D02*
Y119219D01*
X102251D01*
X99228Y123518D01*
D02*
G37*
G36*
X136629Y448410D02*
X136559D01*
X136546D01*
X136532D01*
X136241Y448382D01*
X135991Y448327D01*
X135769Y448244D01*
X135589Y448147D01*
X135450Y448050D01*
X135339Y447966D01*
X135284Y447911D01*
X135256Y447883D01*
X135173Y447786D01*
X135103Y447661D01*
X134992Y447398D01*
X134909Y447107D01*
X134854Y446815D01*
X134826Y446552D01*
X134812Y446441D01*
Y446344D01*
X134798Y446247D01*
Y443667D01*
X138224D01*
Y446413D01*
X138210Y446663D01*
X138196Y446871D01*
X138182Y447037D01*
X138154Y447148D01*
X138140Y447231D01*
X138127Y447287D01*
Y447301D01*
X138057Y447481D01*
X137974Y447634D01*
X137891Y447772D01*
X137794Y447897D01*
X137697Y447980D01*
X137627Y448050D01*
X137572Y448091D01*
X137558Y448105D01*
X137392Y448202D01*
X137225Y448285D01*
X137045Y448341D01*
X136892Y448369D01*
X136754Y448396D01*
X136629Y448410D01*
D02*
G37*
G36*
X348303Y472201D02*
X348220D01*
X347929Y472173D01*
X347665Y472104D01*
X347444Y472020D01*
X347249Y471909D01*
X347097Y471799D01*
X346986Y471715D01*
X346917Y471646D01*
X346889Y471618D01*
X346709Y471382D01*
X346570Y471133D01*
X346473Y470869D01*
X346417Y470620D01*
X346376Y470398D01*
X346362Y470301D01*
Y470218D01*
X346348Y470148D01*
Y470093D01*
Y470065D01*
Y470051D01*
X346376Y469677D01*
X346431Y469358D01*
X346514Y469080D01*
X346612Y468845D01*
X346722Y468664D01*
X346806Y468526D01*
X346861Y468442D01*
X346889Y468428D01*
Y468415D01*
X346986Y468304D01*
X347097Y468220D01*
X347319Y468068D01*
X347541Y467971D01*
X347735Y467888D01*
X347915Y467846D01*
X348054Y467832D01*
X348109Y467818D01*
X348179D01*
X348373Y467832D01*
X348553Y467860D01*
X348719Y467915D01*
X348858Y467971D01*
X348983Y468013D01*
X349080Y468068D01*
X349136Y468096D01*
X349163Y468110D01*
X349330Y468234D01*
X349468Y468359D01*
X349593Y468512D01*
X349690Y468637D01*
X349773Y468761D01*
X349829Y468858D01*
X349870Y468928D01*
X349884Y468955D01*
X349968Y469164D01*
X350023Y469372D01*
X350079Y469566D01*
X350106Y469746D01*
X350120Y469899D01*
X350134Y470023D01*
Y470093D01*
Y470121D01*
X350106Y470453D01*
X350051Y470745D01*
X349954Y471008D01*
X349857Y471216D01*
X349760Y471396D01*
X349663Y471521D01*
X349607Y471590D01*
X349579Y471618D01*
X349357Y471812D01*
X349136Y471951D01*
X348900Y472062D01*
X348692Y472131D01*
X348498Y472173D01*
X348359Y472187D01*
X348303Y472201D01*
D02*
G37*
G36*
X366083Y475474D02*
X363337D01*
X363087Y475460D01*
X362879Y475446D01*
X362713Y475432D01*
X362602Y475404D01*
X362519Y475391D01*
X362463Y475377D01*
X362449D01*
X362269Y475307D01*
X362116Y475224D01*
X361978Y475141D01*
X361853Y475044D01*
X361770Y474947D01*
X361700Y474877D01*
X361659Y474822D01*
X361645Y474808D01*
X361548Y474642D01*
X361465Y474475D01*
X361409Y474295D01*
X361381Y474142D01*
X361354Y474004D01*
X361340Y473879D01*
Y473810D01*
Y473796D01*
Y473782D01*
X361367Y473490D01*
X361423Y473241D01*
X361506Y473019D01*
X361603Y472839D01*
X361700Y472700D01*
X361783Y472589D01*
X361839Y472534D01*
X361867Y472506D01*
X361964Y472423D01*
X362089Y472353D01*
X362352Y472242D01*
X362643Y472159D01*
X362935Y472104D01*
X363198Y472076D01*
X363309Y472062D01*
X363406D01*
X363503Y472048D01*
X366083D01*
Y475474D01*
D02*
G37*
G36*
X428700Y94378D02*
X425955D01*
X425705Y94364D01*
X425497Y94351D01*
X425331Y94337D01*
X425220Y94309D01*
X425136Y94295D01*
X425081Y94281D01*
X425067D01*
X424887Y94212D01*
X424734Y94129D01*
X424595Y94045D01*
X424471Y93948D01*
X424388Y93851D01*
X424318Y93782D01*
X424277Y93726D01*
X424263Y93713D01*
X424166Y93546D01*
X424082Y93380D01*
X424027Y93199D01*
X423999Y93047D01*
X423971Y92908D01*
X423957Y92783D01*
Y92714D01*
Y92700D01*
Y92686D01*
X423985Y92395D01*
X424041Y92145D01*
X424124Y91924D01*
X424221Y91743D01*
X424318Y91604D01*
X424401Y91494D01*
X424457Y91438D01*
X424484Y91410D01*
X424582Y91327D01*
X424706Y91258D01*
X424970Y91147D01*
X425261Y91064D01*
X425552Y91008D01*
X425816Y90980D01*
X425927Y90967D01*
X426024D01*
X426121Y90953D01*
X428700D01*
Y94378D01*
D02*
G37*
G36*
X187546Y448959D02*
X187476D01*
X187462D01*
X187449D01*
X187157Y448931D01*
X186908Y448876D01*
X186686Y448792D01*
X186506Y448695D01*
X186367Y448598D01*
X186256Y448515D01*
X186200Y448460D01*
X186173Y448432D01*
X186089Y448335D01*
X186020Y448210D01*
X185909Y447946D01*
X185826Y447655D01*
X185770Y447364D01*
X185743Y447100D01*
X185729Y446990D01*
Y446892D01*
X185715Y446795D01*
Y444216D01*
X189140D01*
Y446962D01*
X189127Y447211D01*
X189113Y447419D01*
X189099Y447586D01*
X189071Y447697D01*
X189057Y447780D01*
X189043Y447836D01*
Y447849D01*
X188974Y448030D01*
X188891Y448182D01*
X188808Y448321D01*
X188710Y448446D01*
X188613Y448529D01*
X188544Y448598D01*
X188489Y448640D01*
X188475Y448654D01*
X188308Y448751D01*
X188142Y448834D01*
X187962Y448890D01*
X187809Y448917D01*
X187670Y448945D01*
X187546Y448959D01*
D02*
G37*
G36*
X174546Y448839D02*
X174476D01*
X174462D01*
X174449D01*
X174157Y448812D01*
X173908Y448756D01*
X173686Y448673D01*
X173505Y448576D01*
X173367Y448479D01*
X173256Y448396D01*
X173200Y448340D01*
X173173Y448312D01*
X173089Y448215D01*
X173020Y448091D01*
X172909Y447827D01*
X172826Y447536D01*
X172770Y447245D01*
X172743Y446981D01*
X172729Y446870D01*
Y446773D01*
X172715Y446676D01*
Y444096D01*
X176140D01*
Y446842D01*
X176127Y447092D01*
X176113Y447300D01*
X176099Y447467D01*
X176071Y447578D01*
X176057Y447661D01*
X176043Y447716D01*
Y447730D01*
X175974Y447910D01*
X175891Y448063D01*
X175808Y448201D01*
X175711Y448326D01*
X175613Y448410D01*
X175544Y448479D01*
X175489Y448521D01*
X175475Y448534D01*
X175308Y448632D01*
X175142Y448715D01*
X174962Y448770D01*
X174809Y448798D01*
X174670Y448826D01*
X174546Y448839D01*
D02*
G37*
G36*
X450769Y197387D02*
X447746D01*
X447372Y197373D01*
X447053Y197318D01*
X446775Y197248D01*
X446567Y197165D01*
X446387Y197082D01*
X446276Y197013D01*
X446207Y196957D01*
X446179Y196943D01*
X446012Y196763D01*
X445888Y196583D01*
X445804Y196388D01*
X445735Y196222D01*
X445707Y196056D01*
X445694Y195931D01*
X445680Y195848D01*
Y195834D01*
Y195820D01*
X445694Y195653D01*
X445721Y195487D01*
X445763Y195348D01*
X445804Y195224D01*
X445860Y195113D01*
X445901Y195029D01*
X445929Y194974D01*
X445943Y194960D01*
X446040Y194821D01*
X446165Y194697D01*
X446290Y194599D01*
X446415Y194516D01*
X446526Y194461D01*
X446609Y194419D01*
X446664Y194391D01*
X446692Y194378D01*
X446886Y194322D01*
X447108Y194280D01*
X447330Y194253D01*
X447552Y194239D01*
X447746Y194225D01*
X447912Y194211D01*
X450769D01*
Y197387D01*
D02*
G37*
G36*
X393848D02*
X390824D01*
X390450Y197373D01*
X390131Y197318D01*
X389854Y197248D01*
X389646Y197165D01*
X389465Y197082D01*
X389354Y197013D01*
X389285Y196957D01*
X389257Y196943D01*
X389091Y196763D01*
X388966Y196583D01*
X388883Y196388D01*
X388813Y196222D01*
X388786Y196056D01*
X388772Y195931D01*
X388758Y195848D01*
Y195834D01*
Y195820D01*
X388772Y195653D01*
X388800Y195487D01*
X388841Y195348D01*
X388883Y195224D01*
X388938Y195113D01*
X388980Y195029D01*
X389008Y194974D01*
X389021Y194960D01*
X389118Y194821D01*
X389243Y194697D01*
X389368Y194599D01*
X389493Y194516D01*
X389604Y194461D01*
X389687Y194419D01*
X389743Y194391D01*
X389770Y194378D01*
X389964Y194322D01*
X390186Y194280D01*
X390408Y194253D01*
X390630Y194239D01*
X390824Y194225D01*
X390991Y194211D01*
X393848D01*
Y197387D01*
D02*
G37*
G36*
X393679Y308968D02*
X390656D01*
X390282Y308954D01*
X389963Y308899D01*
X389685Y308830D01*
X389477Y308746D01*
X389297Y308663D01*
X389186Y308594D01*
X389117Y308538D01*
X389089Y308524D01*
X388923Y308344D01*
X388798Y308164D01*
X388714Y307970D01*
X388645Y307803D01*
X388617Y307637D01*
X388604Y307512D01*
X388590Y307429D01*
Y307415D01*
Y307401D01*
X388604Y307235D01*
X388631Y307068D01*
X388673Y306930D01*
X388714Y306805D01*
X388770Y306694D01*
X388812Y306611D01*
X388839Y306555D01*
X388853Y306541D01*
X388950Y306403D01*
X389075Y306278D01*
X389200Y306181D01*
X389325Y306098D01*
X389436Y306042D01*
X389519Y306000D01*
X389574Y305973D01*
X389602Y305959D01*
X389796Y305903D01*
X390018Y305862D01*
X390240Y305834D01*
X390462Y305820D01*
X390656Y305806D01*
X390822Y305792D01*
X393679D01*
Y308968D01*
D02*
G37*
G36*
X375276Y309107D02*
X375193D01*
X375040Y309093D01*
X374888Y309079D01*
X374749Y309038D01*
X374624Y308982D01*
X374389Y308857D01*
X374180Y308719D01*
X374028Y308566D01*
X373903Y308441D01*
X373862Y308386D01*
X373834Y308344D01*
X373806Y308330D01*
Y308316D01*
X373709Y308150D01*
X373626Y307956D01*
X373543Y307734D01*
X373487Y307498D01*
X373432Y307249D01*
X373390Y306985D01*
X373321Y306458D01*
X373293Y306195D01*
X373279Y305959D01*
X373265Y305737D01*
Y305557D01*
X373251Y305390D01*
Y305265D01*
Y305196D01*
Y305182D01*
Y305168D01*
Y304738D01*
X373279Y304350D01*
X373307Y304003D01*
X373335Y303671D01*
X373376Y303393D01*
X373432Y303130D01*
X373487Y302908D01*
X373529Y302700D01*
X373584Y302533D01*
X373640Y302395D01*
X373681Y302270D01*
X373737Y302173D01*
X373764Y302103D01*
X373792Y302062D01*
X373820Y302034D01*
Y302020D01*
X373931Y301882D01*
X374042Y301771D01*
X374153Y301660D01*
X374264Y301576D01*
X374499Y301438D01*
X374707Y301341D01*
X374902Y301285D01*
X375040Y301257D01*
X375096Y301244D01*
X375179D01*
X375331Y301257D01*
X375470Y301271D01*
X375734Y301368D01*
X375970Y301493D01*
X376177Y301632D01*
X376330Y301771D01*
X376455Y301895D01*
X376524Y301992D01*
X376552Y302006D01*
Y302020D01*
X376649Y302187D01*
X376732Y302381D01*
X376815Y302603D01*
X376871Y302838D01*
X376926Y303088D01*
X376968Y303352D01*
X377037Y303892D01*
X377065Y304142D01*
X377079Y304378D01*
X377093Y304600D01*
Y304780D01*
X377107Y304946D01*
Y305071D01*
Y305141D01*
Y305168D01*
X377093Y305598D01*
X377079Y305987D01*
X377051Y306347D01*
X377010Y306680D01*
X376968Y306971D01*
X376912Y307235D01*
X376857Y307470D01*
X376802Y307679D01*
X376746Y307859D01*
X376704Y308011D01*
X376649Y308136D01*
X376607Y308247D01*
X376566Y308316D01*
X376538Y308372D01*
X376510Y308400D01*
Y308414D01*
X376413Y308538D01*
X376316Y308649D01*
X376205Y308732D01*
X376094Y308816D01*
X375872Y308941D01*
X375664Y309024D01*
X375484Y309065D01*
X375331Y309093D01*
X375276Y309107D01*
D02*
G37*
G36*
X382005Y265182D02*
X381783D01*
X381645Y265154D01*
X381395Y265085D01*
X381173Y264988D01*
X380979Y264890D01*
X380826Y264779D01*
X380715Y264682D01*
X380646Y264613D01*
X380618Y264599D01*
Y264585D01*
X380438Y264350D01*
X380299Y264086D01*
X380202Y263809D01*
X380147Y263545D01*
X380105Y263323D01*
X380091Y263226D01*
Y263129D01*
X380078Y263060D01*
Y263004D01*
Y262977D01*
Y262963D01*
X380105Y262602D01*
X380161Y262283D01*
X380244Y262020D01*
X380341Y261798D01*
X380452Y261618D01*
X380535Y261493D01*
X380591Y261409D01*
X380618Y261382D01*
X380826Y261188D01*
X381048Y261049D01*
X381270Y260952D01*
X381492Y260882D01*
X381672Y260841D01*
X381825Y260827D01*
X381880Y260813D01*
X381964D01*
X382255Y260841D01*
X382518Y260896D01*
X382754Y260993D01*
X382962Y261104D01*
X383115Y261201D01*
X383240Y261299D01*
X383309Y261354D01*
X383337Y261382D01*
X383517Y261604D01*
X383656Y261853D01*
X383739Y262103D01*
X383808Y262339D01*
X383850Y262547D01*
X383864Y262630D01*
Y262713D01*
X383877Y262782D01*
Y262824D01*
Y262852D01*
Y262866D01*
X383850Y263226D01*
X383794Y263559D01*
X383697Y263850D01*
X383586Y264086D01*
X383489Y264280D01*
X383392Y264419D01*
X383364Y264461D01*
X383337Y264502D01*
X383309Y264516D01*
Y264530D01*
X383198Y264641D01*
X383087Y264752D01*
X382851Y264904D01*
X382615Y265029D01*
X382393Y265098D01*
X382213Y265154D01*
X382061Y265168D01*
X382005Y265182D01*
D02*
G37*
G36*
X400450Y265043D02*
X397427D01*
X397052Y265029D01*
X396734Y264974D01*
X396456Y264904D01*
X396248Y264821D01*
X396068Y264738D01*
X395957Y264669D01*
X395887Y264613D01*
X395860Y264599D01*
X395693Y264419D01*
X395569Y264239D01*
X395485Y264044D01*
X395416Y263878D01*
X395388Y263712D01*
X395374Y263587D01*
X395360Y263504D01*
Y263490D01*
Y263476D01*
X395374Y263309D01*
X395402Y263143D01*
X395444Y263004D01*
X395485Y262880D01*
X395541Y262769D01*
X395582Y262685D01*
X395610Y262630D01*
X395624Y262616D01*
X395721Y262477D01*
X395846Y262353D01*
X395971Y262255D01*
X396096Y262172D01*
X396207Y262117D01*
X396290Y262075D01*
X396345Y262047D01*
X396373Y262034D01*
X396567Y261978D01*
X396789Y261936D01*
X397011Y261909D01*
X397233Y261895D01*
X397427Y261881D01*
X397593Y261867D01*
X400450D01*
Y265043D01*
D02*
G37*
G36*
X312693Y396451D02*
X312610D01*
X312318Y396423D01*
X312055Y396354D01*
X311833Y396270D01*
X311639Y396160D01*
X311486Y396049D01*
X311375Y395965D01*
X311306Y395896D01*
X311278Y395868D01*
X311098Y395633D01*
X310959Y395383D01*
X310862Y395119D01*
X310807Y394870D01*
X310765Y394648D01*
X310751Y394551D01*
Y394468D01*
X310737Y394398D01*
Y394343D01*
Y394315D01*
Y394301D01*
X310765Y393927D01*
X310821Y393608D01*
X310904Y393330D01*
X311001Y393095D01*
X311112Y392914D01*
X311195Y392776D01*
X311250Y392692D01*
X311278Y392678D01*
Y392665D01*
X311375Y392554D01*
X311486Y392471D01*
X311708Y392318D01*
X311930Y392221D01*
X312124Y392138D01*
X312304Y392096D01*
X312443Y392082D01*
X312499Y392068D01*
X312568D01*
X312762Y392082D01*
X312943Y392110D01*
X313109Y392165D01*
X313248Y392221D01*
X313372Y392262D01*
X313470Y392318D01*
X313525Y392346D01*
X313553Y392360D01*
X313719Y392484D01*
X313858Y392609D01*
X313983Y392762D01*
X314080Y392887D01*
X314163Y393011D01*
X314218Y393108D01*
X314260Y393178D01*
X314274Y393205D01*
X314357Y393414D01*
X314412Y393622D01*
X314468Y393816D01*
X314496Y393996D01*
X314510Y394149D01*
X314524Y394273D01*
Y394343D01*
Y394370D01*
X314496Y394703D01*
X314440Y394995D01*
X314343Y395258D01*
X314246Y395466D01*
X314149Y395646D01*
X314052Y395771D01*
X313997Y395840D01*
X313969Y395868D01*
X313747Y396062D01*
X313525Y396201D01*
X313289Y396312D01*
X313081Y396381D01*
X312887Y396423D01*
X312748Y396437D01*
X312693Y396451D01*
D02*
G37*
G36*
X331193Y399793D02*
X328170D01*
X327795Y399779D01*
X327477Y399724D01*
X327199Y399654D01*
X326991Y399571D01*
X326811Y399488D01*
X326700Y399419D01*
X326631Y399363D01*
X326603Y399349D01*
X326436Y399169D01*
X326312Y398989D01*
X326228Y398795D01*
X326159Y398628D01*
X326131Y398462D01*
X326117Y398337D01*
X326104Y398254D01*
Y398240D01*
Y398226D01*
X326117Y398060D01*
X326145Y397893D01*
X326187Y397754D01*
X326228Y397630D01*
X326284Y397519D01*
X326325Y397435D01*
X326353Y397380D01*
X326367Y397366D01*
X326464Y397227D01*
X326589Y397103D01*
X326714Y397006D01*
X326839Y396922D01*
X326950Y396867D01*
X327033Y396825D01*
X327088Y396797D01*
X327116Y396784D01*
X327310Y396728D01*
X327532Y396687D01*
X327754Y396659D01*
X327976Y396645D01*
X328170Y396631D01*
X328336Y396617D01*
X331193D01*
Y399793D01*
D02*
G37*
G36*
X363228Y366793D02*
X360205D01*
X359830Y366779D01*
X359511Y366724D01*
X359234Y366654D01*
X359026Y366571D01*
X358845Y366488D01*
X358735Y366419D01*
X358665Y366363D01*
X358638Y366349D01*
X358471Y366169D01*
X358346Y365989D01*
X358263Y365794D01*
X358194Y365628D01*
X358166Y365462D01*
X358152Y365337D01*
X358138Y365254D01*
Y365240D01*
Y365226D01*
X358152Y365060D01*
X358180Y364893D01*
X358222Y364754D01*
X358263Y364630D01*
X358318Y364519D01*
X358360Y364435D01*
X358388Y364380D01*
X358402Y364366D01*
X358499Y364227D01*
X358624Y364103D01*
X358749Y364006D01*
X358873Y363922D01*
X358984Y363867D01*
X359067Y363825D01*
X359123Y363797D01*
X359151Y363784D01*
X359345Y363728D01*
X359567Y363686D01*
X359789Y363659D01*
X360010Y363645D01*
X360205Y363631D01*
X360371Y363617D01*
X363228D01*
Y366793D01*
D02*
G37*
G36*
X362923Y331210D02*
X359899D01*
X359525Y331196D01*
X359206Y331141D01*
X358928Y331071D01*
X358720Y330988D01*
X358540Y330905D01*
X358429Y330835D01*
X358360Y330780D01*
X358332Y330766D01*
X358166Y330586D01*
X358041Y330405D01*
X357958Y330211D01*
X357888Y330045D01*
X357860Y329878D01*
X357847Y329754D01*
X357833Y329670D01*
Y329656D01*
Y329643D01*
X357847Y329476D01*
X357874Y329310D01*
X357916Y329171D01*
X357958Y329046D01*
X358013Y328935D01*
X358055Y328852D01*
X358082Y328797D01*
X358096Y328783D01*
X358193Y328644D01*
X358318Y328519D01*
X358443Y328422D01*
X358568Y328339D01*
X358679Y328284D01*
X358762Y328242D01*
X358817Y328214D01*
X358845Y328200D01*
X359039Y328145D01*
X359261Y328103D01*
X359483Y328075D01*
X359705Y328062D01*
X359899Y328048D01*
X360066Y328034D01*
X362923D01*
Y331210D01*
D02*
G37*
G36*
X343784Y330364D02*
Y326065D01*
X346807D01*
X343784Y330364D01*
D02*
G37*
G36*
X358145Y399210D02*
X355121D01*
X354747Y399196D01*
X354428Y399141D01*
X354151Y399071D01*
X353943Y398988D01*
X353762Y398905D01*
X353651Y398835D01*
X353582Y398780D01*
X353554Y398766D01*
X353388Y398586D01*
X353263Y398405D01*
X353180Y398211D01*
X353111Y398045D01*
X353083Y397878D01*
X353069Y397754D01*
X353055Y397670D01*
Y397657D01*
Y397643D01*
X353069Y397476D01*
X353097Y397310D01*
X353138Y397171D01*
X353180Y397046D01*
X353235Y396935D01*
X353277Y396852D01*
X353305Y396797D01*
X353318Y396783D01*
X353416Y396644D01*
X353540Y396519D01*
X353665Y396422D01*
X353790Y396339D01*
X353901Y396284D01*
X353984Y396242D01*
X354040Y396214D01*
X354067Y396200D01*
X354262Y396145D01*
X354483Y396103D01*
X354705Y396076D01*
X354927Y396062D01*
X355121Y396048D01*
X355288Y396034D01*
X358145D01*
Y399210D01*
D02*
G37*
G36*
X362764Y354710D02*
X359741D01*
X359366Y354696D01*
X359047Y354641D01*
X358770Y354571D01*
X358562Y354488D01*
X358382Y354405D01*
X358271Y354335D01*
X358201Y354280D01*
X358174Y354266D01*
X358007Y354086D01*
X357882Y353905D01*
X357799Y353711D01*
X357730Y353545D01*
X357702Y353378D01*
X357688Y353254D01*
X357674Y353170D01*
Y353157D01*
Y353143D01*
X357688Y352976D01*
X357716Y352810D01*
X357758Y352671D01*
X357799Y352546D01*
X357855Y352435D01*
X357896Y352352D01*
X357924Y352297D01*
X357938Y352283D01*
X358035Y352144D01*
X358160Y352019D01*
X358285Y351922D01*
X358409Y351839D01*
X358520Y351784D01*
X358604Y351742D01*
X358659Y351714D01*
X358687Y351700D01*
X358881Y351645D01*
X359103Y351603D01*
X359325Y351576D01*
X359547Y351562D01*
X359741Y351548D01*
X359907Y351534D01*
X362764D01*
Y354710D01*
D02*
G37*
G36*
X363179Y343043D02*
X360156D01*
X359782Y343029D01*
X359463Y342974D01*
X359185Y342904D01*
X358977Y342821D01*
X358797Y342738D01*
X358686Y342669D01*
X358617Y342613D01*
X358589Y342599D01*
X358423Y342419D01*
X358298Y342239D01*
X358214Y342044D01*
X358145Y341878D01*
X358117Y341712D01*
X358104Y341587D01*
X358090Y341504D01*
Y341490D01*
Y341476D01*
X358104Y341310D01*
X358131Y341143D01*
X358173Y341004D01*
X358214Y340880D01*
X358270Y340769D01*
X358312Y340685D01*
X358339Y340630D01*
X358353Y340616D01*
X358450Y340477D01*
X358575Y340353D01*
X358700Y340256D01*
X358825Y340172D01*
X358936Y340117D01*
X359019Y340075D01*
X359074Y340047D01*
X359102Y340034D01*
X359296Y339978D01*
X359518Y339936D01*
X359740Y339909D01*
X359962Y339895D01*
X360156Y339881D01*
X360322Y339867D01*
X363179D01*
Y343043D01*
D02*
G37*
G36*
X344776Y343182D02*
X344693D01*
X344540Y343168D01*
X344388Y343154D01*
X344249Y343112D01*
X344124Y343057D01*
X343889Y342932D01*
X343680Y342793D01*
X343528Y342641D01*
X343403Y342516D01*
X343362Y342461D01*
X343334Y342419D01*
X343306Y342405D01*
Y342391D01*
X343209Y342225D01*
X343126Y342031D01*
X343042Y341809D01*
X342987Y341573D01*
X342932Y341323D01*
X342890Y341060D01*
X342821Y340533D01*
X342793Y340269D01*
X342779Y340034D01*
X342765Y339812D01*
Y339631D01*
X342751Y339465D01*
Y339340D01*
Y339271D01*
Y339257D01*
Y339243D01*
Y338813D01*
X342779Y338425D01*
X342807Y338078D01*
X342835Y337745D01*
X342876Y337468D01*
X342932Y337204D01*
X342987Y336982D01*
X343029Y336774D01*
X343084Y336608D01*
X343140Y336469D01*
X343181Y336345D01*
X343237Y336247D01*
X343264Y336178D01*
X343292Y336137D01*
X343320Y336109D01*
Y336095D01*
X343431Y335956D01*
X343542Y335845D01*
X343653Y335734D01*
X343764Y335651D01*
X343999Y335513D01*
X344207Y335415D01*
X344402Y335360D01*
X344540Y335332D01*
X344596Y335318D01*
X344679D01*
X344832Y335332D01*
X344970Y335346D01*
X345234Y335443D01*
X345470Y335568D01*
X345677Y335707D01*
X345830Y335845D01*
X345955Y335970D01*
X346024Y336067D01*
X346052Y336081D01*
Y336095D01*
X346149Y336261D01*
X346232Y336455D01*
X346315Y336677D01*
X346371Y336913D01*
X346426Y337163D01*
X346468Y337426D01*
X346537Y337967D01*
X346565Y338217D01*
X346579Y338453D01*
X346593Y338675D01*
Y338855D01*
X346607Y339021D01*
Y339146D01*
Y339215D01*
Y339243D01*
X346593Y339673D01*
X346579Y340061D01*
X346551Y340422D01*
X346510Y340755D01*
X346468Y341046D01*
X346413Y341310D01*
X346357Y341545D01*
X346302Y341753D01*
X346246Y341934D01*
X346204Y342086D01*
X346149Y342211D01*
X346107Y342322D01*
X346066Y342391D01*
X346038Y342447D01*
X346010Y342474D01*
Y342488D01*
X345913Y342613D01*
X345816Y342724D01*
X345705Y342807D01*
X345594Y342891D01*
X345372Y343015D01*
X345164Y343098D01*
X344984Y343140D01*
X344832Y343168D01*
X344776Y343182D01*
D02*
G37*
G36*
X49755Y357932D02*
X49533D01*
X49395Y357904D01*
X49145Y357835D01*
X48923Y357738D01*
X48729Y357640D01*
X48576Y357529D01*
X48465Y357432D01*
X48396Y357363D01*
X48368Y357349D01*
Y357335D01*
X48188Y357100D01*
X48049Y356836D01*
X47952Y356559D01*
X47897Y356295D01*
X47855Y356073D01*
X47841Y355976D01*
Y355879D01*
X47828Y355810D01*
Y355754D01*
Y355727D01*
Y355713D01*
X47855Y355352D01*
X47911Y355033D01*
X47994Y354770D01*
X48091Y354548D01*
X48202Y354367D01*
X48285Y354243D01*
X48341Y354160D01*
X48368Y354132D01*
X48576Y353938D01*
X48798Y353799D01*
X49020Y353702D01*
X49242Y353633D01*
X49422Y353591D01*
X49575Y353577D01*
X49630Y353563D01*
X49714D01*
X50005Y353591D01*
X50268Y353646D01*
X50504Y353743D01*
X50712Y353854D01*
X50865Y353951D01*
X50989Y354049D01*
X51059Y354104D01*
X51087Y354132D01*
X51267Y354354D01*
X51406Y354603D01*
X51489Y354853D01*
X51558Y355089D01*
X51600Y355297D01*
X51614Y355380D01*
Y355463D01*
X51627Y355532D01*
Y355574D01*
Y355602D01*
Y355616D01*
X51600Y355976D01*
X51544Y356309D01*
X51447Y356600D01*
X51336Y356836D01*
X51239Y357030D01*
X51142Y357169D01*
X51114Y357211D01*
X51087Y357252D01*
X51059Y357266D01*
Y357280D01*
X50948Y357391D01*
X50837Y357502D01*
X50601Y357654D01*
X50366Y357779D01*
X50144Y357849D01*
X49963Y357904D01*
X49811Y357918D01*
X49755Y357932D01*
D02*
G37*
G36*
X68200Y357793D02*
X65177D01*
X64802Y357779D01*
X64483Y357724D01*
X64206Y357654D01*
X63998Y357571D01*
X63818Y357488D01*
X63707Y357419D01*
X63637Y357363D01*
X63610Y357349D01*
X63443Y357169D01*
X63319Y356989D01*
X63235Y356795D01*
X63166Y356628D01*
X63138Y356462D01*
X63124Y356337D01*
X63110Y356254D01*
Y356240D01*
Y356226D01*
X63124Y356059D01*
X63152Y355893D01*
X63194Y355754D01*
X63235Y355630D01*
X63291Y355519D01*
X63332Y355435D01*
X63360Y355380D01*
X63374Y355366D01*
X63471Y355227D01*
X63596Y355103D01*
X63721Y355005D01*
X63846Y354922D01*
X63956Y354867D01*
X64040Y354825D01*
X64095Y354797D01*
X64123Y354784D01*
X64317Y354728D01*
X64539Y354687D01*
X64761Y354659D01*
X64983Y354645D01*
X65177Y354631D01*
X65343Y354617D01*
X68200D01*
Y357793D01*
D02*
G37*
G36*
X67700Y345543D02*
X64677D01*
X64303Y345529D01*
X63983Y345474D01*
X63706Y345404D01*
X63498Y345321D01*
X63318Y345238D01*
X63207Y345169D01*
X63137Y345113D01*
X63110Y345099D01*
X62943Y344919D01*
X62818Y344739D01*
X62735Y344544D01*
X62666Y344378D01*
X62638Y344212D01*
X62624Y344087D01*
X62611Y344004D01*
Y343990D01*
Y343976D01*
X62624Y343809D01*
X62652Y343643D01*
X62694Y343504D01*
X62735Y343380D01*
X62791Y343269D01*
X62832Y343185D01*
X62860Y343130D01*
X62874Y343116D01*
X62971Y342977D01*
X63096Y342853D01*
X63221Y342755D01*
X63345Y342672D01*
X63457Y342617D01*
X63540Y342575D01*
X63595Y342547D01*
X63623Y342534D01*
X63817Y342478D01*
X64039Y342436D01*
X64261Y342409D01*
X64483Y342395D01*
X64677Y342381D01*
X64843Y342367D01*
X67700D01*
Y345543D01*
D02*
G37*
G36*
X49297Y345682D02*
X49186D01*
X48950Y345668D01*
X48728Y345612D01*
X48548Y345543D01*
X48382Y345460D01*
X48257Y345377D01*
X48160Y345307D01*
X48090Y345252D01*
X48076Y345238D01*
X47924Y345058D01*
X47813Y344877D01*
X47730Y344697D01*
X47674Y344531D01*
X47646Y344378D01*
X47619Y344253D01*
Y344170D01*
Y344156D01*
Y344142D01*
X47633Y343920D01*
X47688Y343712D01*
X47758Y343532D01*
X47841Y343380D01*
X47924Y343255D01*
X47993Y343172D01*
X48049Y343102D01*
X48063Y343088D01*
X48229Y342950D01*
X48423Y342839D01*
X48603Y342769D01*
X48784Y342714D01*
X48950Y342686D01*
X49075Y342672D01*
X49158Y342658D01*
X49186D01*
X49436Y342672D01*
X49657Y342728D01*
X49852Y342797D01*
X50018Y342880D01*
X50143Y342950D01*
X50240Y343019D01*
X50309Y343074D01*
X50323Y343088D01*
X50462Y343255D01*
X50573Y343449D01*
X50642Y343629D01*
X50698Y343809D01*
X50725Y343962D01*
X50739Y344087D01*
X50753Y344170D01*
Y344184D01*
Y344198D01*
X50739Y344420D01*
X50684Y344614D01*
X50614Y344794D01*
X50531Y344947D01*
X50462Y345071D01*
X50392Y345169D01*
X50337Y345224D01*
X50323Y345238D01*
X50143Y345390D01*
X49963Y345501D01*
X49768Y345571D01*
X49588Y345626D01*
X49422Y345654D01*
X49297Y345682D01*
D02*
G37*
G36*
X49311Y341702D02*
X49227D01*
X48922Y341674D01*
X48645Y341618D01*
X48395Y341521D01*
X48187Y341424D01*
X48021Y341313D01*
X47896Y341216D01*
X47827Y341161D01*
X47799Y341133D01*
X47605Y340911D01*
X47466Y340675D01*
X47369Y340439D01*
X47300Y340231D01*
X47258Y340023D01*
X47244Y339871D01*
X47231Y339815D01*
Y339774D01*
Y339746D01*
Y339732D01*
X47258Y339441D01*
X47314Y339164D01*
X47411Y338928D01*
X47508Y338734D01*
X47605Y338581D01*
X47702Y338456D01*
X47758Y338387D01*
X47785Y338359D01*
X48007Y338179D01*
X48229Y338040D01*
X48465Y337957D01*
X48687Y337888D01*
X48881Y337846D01*
X49047Y337832D01*
X49103Y337818D01*
X49186D01*
X49380Y337832D01*
X49574Y337860D01*
X49755Y337901D01*
X49907Y337943D01*
X50032Y337985D01*
X50129Y338026D01*
X50184Y338054D01*
X50212Y338068D01*
X50379Y338179D01*
X50517Y338290D01*
X50642Y338415D01*
X50739Y338540D01*
X50822Y338637D01*
X50878Y338720D01*
X50906Y338789D01*
X50919Y338803D01*
X50989Y338983D01*
X51044Y339150D01*
X51086Y339316D01*
X51114Y339469D01*
X51128Y339594D01*
X51141Y339691D01*
Y339746D01*
Y339774D01*
X51114Y340065D01*
X51058Y340328D01*
X50975Y340564D01*
X50864Y340772D01*
X50767Y340925D01*
X50684Y341050D01*
X50628Y341119D01*
X50601Y341147D01*
X50392Y341327D01*
X50157Y341466D01*
X49935Y341563D01*
X49713Y341632D01*
X49519Y341674D01*
X49366Y341688D01*
X49311Y341702D01*
D02*
G37*
G36*
X29693Y338210D02*
X26670D01*
X26295Y338196D01*
X25977Y338140D01*
X25699Y338071D01*
X25491Y337988D01*
X25311Y337905D01*
X25200Y337835D01*
X25131Y337780D01*
X25103Y337766D01*
X24936Y337586D01*
X24812Y337405D01*
X24728Y337211D01*
X24659Y337045D01*
X24631Y336878D01*
X24618Y336754D01*
X24604Y336670D01*
Y336656D01*
Y336643D01*
X24618Y336476D01*
X24645Y336310D01*
X24687Y336171D01*
X24728Y336046D01*
X24784Y335935D01*
X24825Y335852D01*
X24853Y335797D01*
X24867Y335783D01*
X24964Y335644D01*
X25089Y335519D01*
X25214Y335422D01*
X25339Y335339D01*
X25450Y335284D01*
X25533Y335242D01*
X25588Y335214D01*
X25616Y335200D01*
X25810Y335145D01*
X26032Y335103D01*
X26254Y335075D01*
X26476Y335062D01*
X26670Y335048D01*
X26836Y335034D01*
X29693D01*
Y338210D01*
D02*
G37*
G36*
X31478Y414543D02*
X28455D01*
X28080Y414529D01*
X27761Y414474D01*
X27484Y414404D01*
X27276Y414321D01*
X27095Y414238D01*
X26985Y414169D01*
X26915Y414113D01*
X26888Y414099D01*
X26721Y413919D01*
X26596Y413739D01*
X26513Y413545D01*
X26444Y413378D01*
X26416Y413212D01*
X26402Y413087D01*
X26388Y413004D01*
Y412990D01*
Y412976D01*
X26402Y412809D01*
X26430Y412643D01*
X26471Y412504D01*
X26513Y412379D01*
X26569Y412269D01*
X26610Y412185D01*
X26638Y412130D01*
X26652Y412116D01*
X26749Y411977D01*
X26874Y411852D01*
X26998Y411755D01*
X27123Y411672D01*
X27234Y411617D01*
X27317Y411575D01*
X27373Y411547D01*
X27401Y411534D01*
X27595Y411478D01*
X27817Y411437D01*
X28039Y411409D01*
X28261Y411395D01*
X28455Y411381D01*
X28621Y411367D01*
X31478D01*
Y414543D01*
D02*
G37*
G36*
X282193Y326293D02*
X279170D01*
X278796Y326279D01*
X278477Y326224D01*
X278199Y326154D01*
X277991Y326071D01*
X277811Y325988D01*
X277700Y325919D01*
X277631Y325863D01*
X277603Y325849D01*
X277436Y325669D01*
X277312Y325489D01*
X277228Y325294D01*
X277159Y325128D01*
X277131Y324962D01*
X277117Y324837D01*
X277104Y324754D01*
Y324740D01*
Y324726D01*
X277117Y324559D01*
X277145Y324393D01*
X277187Y324254D01*
X277228Y324129D01*
X277284Y324019D01*
X277325Y323935D01*
X277353Y323880D01*
X277367Y323866D01*
X277464Y323727D01*
X277589Y323602D01*
X277714Y323505D01*
X277839Y323422D01*
X277950Y323367D01*
X278033Y323325D01*
X278088Y323297D01*
X278116Y323284D01*
X278310Y323228D01*
X278532Y323186D01*
X278754Y323159D01*
X278976Y323145D01*
X279170Y323131D01*
X279336Y323117D01*
X282193D01*
Y326293D01*
D02*
G37*
G36*
X138087Y343411D02*
X138004D01*
X137713Y343383D01*
X137449Y343314D01*
X137227Y343231D01*
X137033Y343120D01*
X136881Y343009D01*
X136770Y342925D01*
X136700Y342856D01*
X136673Y342828D01*
X136492Y342593D01*
X136354Y342343D01*
X136257Y342079D01*
X136201Y341830D01*
X136160Y341608D01*
X136146Y341511D01*
Y341428D01*
X136132Y341358D01*
Y341303D01*
Y341275D01*
Y341261D01*
X136160Y340887D01*
X136215Y340568D01*
X136298Y340290D01*
X136395Y340055D01*
X136506Y339874D01*
X136589Y339736D01*
X136645Y339652D01*
X136673Y339638D01*
Y339625D01*
X136770Y339514D01*
X136881Y339431D01*
X137103Y339278D01*
X137324Y339181D01*
X137519Y339098D01*
X137699Y339056D01*
X137838Y339042D01*
X137893Y339028D01*
X137963D01*
X138157Y339042D01*
X138337Y339070D01*
X138503Y339125D01*
X138642Y339181D01*
X138767Y339222D01*
X138864Y339278D01*
X138919Y339306D01*
X138947Y339320D01*
X139114Y339444D01*
X139252Y339569D01*
X139377Y339722D01*
X139474Y339847D01*
X139557Y339971D01*
X139613Y340069D01*
X139654Y340138D01*
X139668Y340165D01*
X139752Y340374D01*
X139807Y340582D01*
X139862Y340776D01*
X139890Y340956D01*
X139904Y341109D01*
X139918Y341233D01*
Y341303D01*
Y341330D01*
X139890Y341663D01*
X139835Y341955D01*
X139738Y342218D01*
X139641Y342426D01*
X139544Y342606D01*
X139446Y342731D01*
X139391Y342800D01*
X139363Y342828D01*
X139141Y343022D01*
X138919Y343161D01*
X138684Y343272D01*
X138476Y343341D01*
X138281Y343383D01*
X138143Y343397D01*
X138087Y343411D01*
D02*
G37*
G36*
X156588Y346753D02*
X153564D01*
X153190Y346739D01*
X152871Y346684D01*
X152594Y346614D01*
X152386Y346531D01*
X152205Y346448D01*
X152094Y346379D01*
X152025Y346323D01*
X151997Y346309D01*
X151831Y346129D01*
X151706Y345949D01*
X151623Y345755D01*
X151553Y345588D01*
X151526Y345422D01*
X151512Y345297D01*
X151498Y345214D01*
Y345200D01*
Y345186D01*
X151512Y345019D01*
X151540Y344853D01*
X151581Y344714D01*
X151623Y344590D01*
X151678Y344479D01*
X151720Y344395D01*
X151748Y344340D01*
X151762Y344326D01*
X151859Y344187D01*
X151983Y344063D01*
X152108Y343965D01*
X152233Y343882D01*
X152344Y343827D01*
X152427Y343785D01*
X152483Y343758D01*
X152510Y343744D01*
X152705Y343688D01*
X152927Y343647D01*
X153148Y343619D01*
X153370Y343605D01*
X153564Y343591D01*
X153731Y343577D01*
X156588D01*
Y346753D01*
D02*
G37*
G36*
X67673Y333210D02*
X64649D01*
X64275Y333196D01*
X63956Y333140D01*
X63678Y333071D01*
X63470Y332988D01*
X63290Y332905D01*
X63179Y332835D01*
X63110Y332780D01*
X63082Y332766D01*
X62916Y332586D01*
X62791Y332405D01*
X62708Y332211D01*
X62638Y332045D01*
X62611Y331878D01*
X62597Y331754D01*
X62583Y331670D01*
Y331656D01*
Y331643D01*
X62597Y331476D01*
X62624Y331310D01*
X62666Y331171D01*
X62708Y331046D01*
X62763Y330935D01*
X62805Y330852D01*
X62832Y330797D01*
X62846Y330783D01*
X62943Y330644D01*
X63068Y330519D01*
X63193Y330422D01*
X63318Y330339D01*
X63429Y330284D01*
X63512Y330242D01*
X63567Y330214D01*
X63595Y330200D01*
X63789Y330145D01*
X64011Y330103D01*
X64233Y330075D01*
X64455Y330062D01*
X64649Y330048D01*
X64816Y330034D01*
X67673D01*
Y333210D01*
D02*
G37*
G36*
X48534Y332364D02*
Y328065D01*
X51557D01*
X48534Y332364D01*
D02*
G37*
G36*
X67693Y320793D02*
X64670D01*
X64296Y320779D01*
X63977Y320724D01*
X63699Y320654D01*
X63491Y320571D01*
X63311Y320488D01*
X63200Y320419D01*
X63131Y320363D01*
X63103Y320349D01*
X62936Y320169D01*
X62812Y319989D01*
X62728Y319795D01*
X62659Y319628D01*
X62631Y319462D01*
X62618Y319337D01*
X62604Y319254D01*
Y319240D01*
Y319226D01*
X62618Y319060D01*
X62645Y318893D01*
X62687Y318754D01*
X62728Y318629D01*
X62784Y318519D01*
X62825Y318435D01*
X62853Y318380D01*
X62867Y318366D01*
X62964Y318227D01*
X63089Y318102D01*
X63214Y318006D01*
X63339Y317922D01*
X63450Y317867D01*
X63533Y317825D01*
X63588Y317797D01*
X63616Y317784D01*
X63810Y317728D01*
X64032Y317687D01*
X64254Y317659D01*
X64476Y317645D01*
X64670Y317631D01*
X64836Y317617D01*
X67693D01*
Y320793D01*
D02*
G37*
G36*
X276650Y215301D02*
X273627D01*
X273252Y215287D01*
X272933Y215232D01*
X272656Y215163D01*
X272448Y215079D01*
X272268Y214996D01*
X272157Y214927D01*
X272087Y214871D01*
X272060Y214857D01*
X271893Y214677D01*
X271768Y214497D01*
X271685Y214303D01*
X271616Y214136D01*
X271588Y213970D01*
X271574Y213845D01*
X271560Y213762D01*
Y213748D01*
Y213734D01*
X271574Y213568D01*
X271602Y213401D01*
X271644Y213263D01*
X271685Y213138D01*
X271741Y213027D01*
X271782Y212943D01*
X271810Y212888D01*
X271824Y212874D01*
X271921Y212736D01*
X272046Y212611D01*
X272171Y212514D01*
X272295Y212430D01*
X272406Y212375D01*
X272490Y212333D01*
X272545Y212306D01*
X272573Y212292D01*
X272767Y212236D01*
X272989Y212195D01*
X273211Y212167D01*
X273433Y212153D01*
X273627Y212139D01*
X273793Y212125D01*
X276650D01*
Y215301D01*
D02*
G37*
G36*
X252519D02*
X249496D01*
X249122Y215287D01*
X248803Y215232D01*
X248525Y215163D01*
X248317Y215079D01*
X248137Y214996D01*
X248026Y214927D01*
X247957Y214871D01*
X247929Y214857D01*
X247763Y214677D01*
X247638Y214497D01*
X247555Y214303D01*
X247485Y214136D01*
X247458Y213970D01*
X247444Y213845D01*
X247430Y213762D01*
Y213748D01*
Y213734D01*
X247444Y213568D01*
X247471Y213401D01*
X247513Y213263D01*
X247555Y213138D01*
X247610Y213027D01*
X247652Y212943D01*
X247680Y212888D01*
X247693Y212874D01*
X247790Y212736D01*
X247915Y212611D01*
X248040Y212514D01*
X248165Y212430D01*
X248276Y212375D01*
X248359Y212333D01*
X248414Y212306D01*
X248442Y212292D01*
X248636Y212236D01*
X248858Y212195D01*
X249080Y212167D01*
X249302Y212153D01*
X249496Y212139D01*
X249663Y212125D01*
X252519D01*
Y215301D01*
D02*
G37*
G36*
X229935Y215384D02*
X226912D01*
X226537Y215371D01*
X226218Y215315D01*
X225941Y215246D01*
X225733Y215163D01*
X225552Y215079D01*
X225441Y215010D01*
X225372Y214954D01*
X225344Y214941D01*
X225178Y214760D01*
X225053Y214580D01*
X224970Y214386D01*
X224901Y214219D01*
X224873Y214053D01*
X224859Y213928D01*
X224845Y213845D01*
Y213831D01*
Y213817D01*
X224859Y213651D01*
X224887Y213484D01*
X224928Y213346D01*
X224970Y213221D01*
X225025Y213110D01*
X225067Y213027D01*
X225095Y212971D01*
X225109Y212957D01*
X225206Y212819D01*
X225331Y212694D01*
X225455Y212597D01*
X225580Y212514D01*
X225691Y212458D01*
X225774Y212416D01*
X225830Y212389D01*
X225858Y212375D01*
X226052Y212319D01*
X226274Y212278D01*
X226495Y212250D01*
X226717Y212236D01*
X226912Y212222D01*
X227078Y212208D01*
X229935D01*
Y215384D01*
D02*
G37*
G36*
X211532Y215523D02*
X211448D01*
X211296Y215509D01*
X211143Y215495D01*
X211005Y215454D01*
X210880Y215398D01*
X210644Y215273D01*
X210436Y215135D01*
X210283Y214982D01*
X210159Y214857D01*
X210117Y214802D01*
X210089Y214760D01*
X210061Y214746D01*
Y214732D01*
X209964Y214566D01*
X209881Y214372D01*
X209798Y214150D01*
X209743Y213914D01*
X209687Y213665D01*
X209645Y213401D01*
X209576Y212874D01*
X209548Y212611D01*
X209534Y212375D01*
X209521Y212153D01*
Y211973D01*
X209507Y211806D01*
Y211681D01*
Y211612D01*
Y211598D01*
Y211584D01*
Y211154D01*
X209534Y210766D01*
X209562Y210420D01*
X209590Y210087D01*
X209632Y209809D01*
X209687Y209546D01*
X209743Y209324D01*
X209784Y209116D01*
X209839Y208949D01*
X209895Y208811D01*
X209937Y208686D01*
X209992Y208589D01*
X210020Y208519D01*
X210048Y208478D01*
X210075Y208450D01*
Y208436D01*
X210186Y208298D01*
X210297Y208187D01*
X210408Y208076D01*
X210519Y207992D01*
X210755Y207854D01*
X210963Y207757D01*
X211157Y207701D01*
X211296Y207673D01*
X211351Y207660D01*
X211434D01*
X211587Y207673D01*
X211726Y207687D01*
X211989Y207785D01*
X212225Y207909D01*
X212433Y208048D01*
X212586Y208187D01*
X212710Y208312D01*
X212780Y208409D01*
X212807Y208422D01*
Y208436D01*
X212904Y208603D01*
X212988Y208797D01*
X213071Y209019D01*
X213126Y209254D01*
X213182Y209504D01*
X213223Y209768D01*
X213293Y210308D01*
X213321Y210558D01*
X213334Y210794D01*
X213348Y211016D01*
Y211196D01*
X213362Y211362D01*
Y211487D01*
Y211557D01*
Y211584D01*
X213348Y212014D01*
X213334Y212403D01*
X213307Y212763D01*
X213265Y213096D01*
X213223Y213387D01*
X213168Y213651D01*
X213113Y213887D01*
X213057Y214095D01*
X213001Y214275D01*
X212960Y214427D01*
X212904Y214552D01*
X212863Y214663D01*
X212821Y214732D01*
X212794Y214788D01*
X212766Y214816D01*
Y214830D01*
X212669Y214954D01*
X212572Y215065D01*
X212461Y215149D01*
X212350Y215232D01*
X212128Y215357D01*
X211920Y215440D01*
X211740Y215481D01*
X211587Y215509D01*
X211532Y215523D01*
D02*
G37*
G36*
X289241Y202873D02*
X289019D01*
X288881Y202845D01*
X288631Y202776D01*
X288409Y202679D01*
X288215Y202582D01*
X288062Y202471D01*
X287952Y202374D01*
X287882Y202304D01*
X287854Y202290D01*
Y202277D01*
X287674Y202041D01*
X287535Y201777D01*
X287438Y201500D01*
X287383Y201236D01*
X287341Y201015D01*
X287327Y200918D01*
Y200821D01*
X287314Y200751D01*
Y200696D01*
Y200668D01*
Y200654D01*
X287341Y200294D01*
X287397Y199974D01*
X287480Y199711D01*
X287577Y199489D01*
X287688Y199309D01*
X287771Y199184D01*
X287827Y199101D01*
X287854Y199073D01*
X288062Y198879D01*
X288284Y198740D01*
X288506Y198643D01*
X288728Y198574D01*
X288908Y198532D01*
X289061Y198518D01*
X289116Y198505D01*
X289200D01*
X289491Y198532D01*
X289754Y198588D01*
X289990Y198685D01*
X290198Y198796D01*
X290351Y198893D01*
X290476Y198990D01*
X290545Y199045D01*
X290573Y199073D01*
X290753Y199295D01*
X290892Y199545D01*
X290975Y199794D01*
X291044Y200030D01*
X291086Y200238D01*
X291100Y200321D01*
Y200404D01*
X291113Y200474D01*
Y200515D01*
Y200543D01*
Y200557D01*
X291086Y200918D01*
X291030Y201250D01*
X290933Y201542D01*
X290822Y201777D01*
X290725Y201972D01*
X290628Y202110D01*
X290600Y202152D01*
X290573Y202193D01*
X290545Y202207D01*
Y202221D01*
X290434Y202332D01*
X290323Y202443D01*
X290087Y202596D01*
X289851Y202720D01*
X289630Y202790D01*
X289449Y202845D01*
X289297Y202859D01*
X289241Y202873D01*
D02*
G37*
G36*
X300225Y202734D02*
X297202D01*
X296827Y202720D01*
X296508Y202665D01*
X296231Y202596D01*
X296023Y202512D01*
X295843Y202429D01*
X295732Y202360D01*
X295662Y202304D01*
X295635Y202290D01*
X295468Y202110D01*
X295343Y201930D01*
X295260Y201736D01*
X295191Y201569D01*
X295163Y201403D01*
X295149Y201278D01*
X295135Y201195D01*
Y201181D01*
Y201167D01*
X295149Y201001D01*
X295177Y200834D01*
X295219Y200696D01*
X295260Y200571D01*
X295316Y200460D01*
X295357Y200377D01*
X295385Y200321D01*
X295399Y200307D01*
X295496Y200169D01*
X295621Y200044D01*
X295746Y199947D01*
X295870Y199864D01*
X295981Y199808D01*
X296064Y199767D01*
X296120Y199739D01*
X296148Y199725D01*
X296342Y199669D01*
X296564Y199628D01*
X296786Y199600D01*
X297008Y199586D01*
X297202Y199572D01*
X297368Y199559D01*
X300225D01*
Y202734D01*
D02*
G37*
G36*
X314880Y429597D02*
X314769D01*
X314533Y429583D01*
X314311Y429527D01*
X314131Y429458D01*
X313965Y429375D01*
X313840Y429292D01*
X313743Y429222D01*
X313673Y429167D01*
X313659Y429153D01*
X313507Y428973D01*
X313396Y428792D01*
X313313Y428612D01*
X313257Y428446D01*
X313230Y428293D01*
X313202Y428168D01*
Y428085D01*
Y428071D01*
Y428057D01*
X313216Y427836D01*
X313271Y427627D01*
X313340Y427447D01*
X313424Y427295D01*
X313507Y427170D01*
X313576Y427087D01*
X313632Y427017D01*
X313646Y427003D01*
X313812Y426865D01*
X314006Y426754D01*
X314186Y426684D01*
X314367Y426629D01*
X314533Y426601D01*
X314658Y426587D01*
X314741Y426573D01*
X314769D01*
X315019Y426587D01*
X315240Y426643D01*
X315435Y426712D01*
X315601Y426795D01*
X315726Y426865D01*
X315823Y426934D01*
X315892Y426990D01*
X315906Y427003D01*
X316045Y427170D01*
X316156Y427364D01*
X316225Y427544D01*
X316281Y427724D01*
X316308Y427877D01*
X316322Y428002D01*
X316336Y428085D01*
Y428099D01*
Y428113D01*
X316322Y428335D01*
X316267Y428529D01*
X316197Y428709D01*
X316114Y428862D01*
X316045Y428987D01*
X315975Y429084D01*
X315920Y429139D01*
X315906Y429153D01*
X315726Y429305D01*
X315546Y429417D01*
X315351Y429486D01*
X315171Y429541D01*
X315005Y429569D01*
X314880Y429597D01*
D02*
G37*
G36*
X314894Y425616D02*
X314811D01*
X314505Y425589D01*
X314228Y425533D01*
X313978Y425436D01*
X313770Y425339D01*
X313604Y425228D01*
X313479Y425131D01*
X313410Y425076D01*
X313382Y425048D01*
X313188Y424826D01*
X313049Y424590D01*
X312952Y424355D01*
X312883Y424146D01*
X312841Y423938D01*
X312827Y423786D01*
X312813Y423730D01*
Y423689D01*
Y423661D01*
Y423647D01*
X312841Y423356D01*
X312897Y423079D01*
X312994Y422843D01*
X313091Y422649D01*
X313188Y422496D01*
X313285Y422371D01*
X313340Y422302D01*
X313368Y422274D01*
X313590Y422094D01*
X313812Y421955D01*
X314048Y421872D01*
X314270Y421803D01*
X314464Y421761D01*
X314630Y421747D01*
X314686Y421733D01*
X314769D01*
X314963Y421747D01*
X315157Y421775D01*
X315338Y421817D01*
X315490Y421858D01*
X315615Y421900D01*
X315712Y421941D01*
X315767Y421969D01*
X315795Y421983D01*
X315962Y422094D01*
X316100Y422205D01*
X316225Y422330D01*
X316322Y422455D01*
X316405Y422552D01*
X316461Y422635D01*
X316489Y422704D01*
X316502Y422718D01*
X316572Y422898D01*
X316627Y423065D01*
X316669Y423231D01*
X316697Y423384D01*
X316710Y423509D01*
X316724Y423606D01*
Y423661D01*
Y423689D01*
X316697Y423980D01*
X316641Y424244D01*
X316558Y424479D01*
X316447Y424687D01*
X316350Y424840D01*
X316267Y424965D01*
X316211Y425034D01*
X316183Y425062D01*
X315975Y425242D01*
X315740Y425381D01*
X315518Y425478D01*
X315296Y425547D01*
X315102Y425589D01*
X314949Y425603D01*
X314894Y425616D01*
D02*
G37*
G36*
X136765Y200718D02*
Y196419D01*
X139788D01*
X136765Y200718D01*
D02*
G37*
G36*
X103583Y242951D02*
X100559D01*
X100185Y242937D01*
X99866Y242881D01*
X99589Y242812D01*
X99381Y242729D01*
X99200Y242646D01*
X99089Y242576D01*
X99020Y242521D01*
X98992Y242507D01*
X98826Y242327D01*
X98701Y242146D01*
X98618Y241952D01*
X98548Y241786D01*
X98521Y241619D01*
X98507Y241495D01*
X98493Y241411D01*
Y241397D01*
Y241384D01*
X98507Y241217D01*
X98535Y241051D01*
X98576Y240912D01*
X98618Y240787D01*
X98673Y240676D01*
X98715Y240593D01*
X98743Y240538D01*
X98757Y240524D01*
X98854Y240385D01*
X98978Y240260D01*
X99103Y240163D01*
X99228Y240080D01*
X99339Y240025D01*
X99422Y239983D01*
X99478Y239955D01*
X99505Y239941D01*
X99700Y239886D01*
X99922Y239844D01*
X100143Y239816D01*
X100365Y239803D01*
X100559Y239789D01*
X100726Y239775D01*
X103583D01*
Y242951D01*
D02*
G37*
G36*
X146900Y169735D02*
Y165435D01*
X149923D01*
X146900Y169735D01*
D02*
G37*
G36*
X403833Y394550D02*
X403722D01*
X403487Y394536D01*
X403265Y394481D01*
X403084Y394411D01*
X402918Y394328D01*
X402793Y394245D01*
X402696Y394176D01*
X402627Y394120D01*
X402613Y394106D01*
X402460Y393926D01*
X402349Y393746D01*
X402266Y393565D01*
X402211Y393399D01*
X402183Y393246D01*
X402155Y393122D01*
Y393038D01*
Y393024D01*
Y393011D01*
X402169Y392789D01*
X402225Y392581D01*
X402294Y392400D01*
X402377Y392248D01*
X402460Y392123D01*
X402530Y392040D01*
X402585Y391970D01*
X402599Y391957D01*
X402765Y391818D01*
X402960Y391707D01*
X403140Y391638D01*
X403320Y391582D01*
X403487Y391554D01*
X403611Y391541D01*
X403695Y391527D01*
X403722D01*
X403972Y391541D01*
X404194Y391596D01*
X404388Y391665D01*
X404554Y391749D01*
X404679Y391818D01*
X404776Y391887D01*
X404846Y391943D01*
X404860Y391957D01*
X404998Y392123D01*
X405109Y392317D01*
X405178Y392497D01*
X405234Y392678D01*
X405262Y392830D01*
X405276Y392955D01*
X405289Y393038D01*
Y393052D01*
Y393066D01*
X405276Y393288D01*
X405220Y393482D01*
X405151Y393662D01*
X405068Y393815D01*
X404998Y393940D01*
X404929Y394037D01*
X404873Y394092D01*
X404860Y394106D01*
X404679Y394259D01*
X404499Y394370D01*
X404305Y394439D01*
X404124Y394495D01*
X403958Y394522D01*
X403833Y394550D01*
D02*
G37*
G36*
X403847Y390570D02*
X403764D01*
X403459Y390542D01*
X403181Y390487D01*
X402932Y390390D01*
X402724Y390292D01*
X402557Y390182D01*
X402433Y390084D01*
X402363Y390029D01*
X402336Y390001D01*
X402141Y389779D01*
X402003Y389543D01*
X401906Y389308D01*
X401836Y389100D01*
X401795Y388892D01*
X401781Y388739D01*
X401767Y388684D01*
Y388642D01*
Y388614D01*
Y388601D01*
X401795Y388309D01*
X401850Y388032D01*
X401947Y387796D01*
X402044Y387602D01*
X402141Y387449D01*
X402238Y387325D01*
X402294Y387255D01*
X402322Y387228D01*
X402543Y387047D01*
X402765Y386908D01*
X403001Y386825D01*
X403223Y386756D01*
X403417Y386714D01*
X403584Y386701D01*
X403639Y386687D01*
X403722D01*
X403917Y386701D01*
X404111Y386728D01*
X404291Y386770D01*
X404444Y386811D01*
X404568Y386853D01*
X404665Y386895D01*
X404721Y386922D01*
X404749Y386936D01*
X404915Y387047D01*
X405054Y387158D01*
X405178Y387283D01*
X405276Y387408D01*
X405359Y387505D01*
X405414Y387588D01*
X405442Y387657D01*
X405456Y387671D01*
X405525Y387852D01*
X405581Y388018D01*
X405622Y388184D01*
X405650Y388337D01*
X405664Y388462D01*
X405678Y388559D01*
Y388614D01*
Y388642D01*
X405650Y388933D01*
X405595Y389197D01*
X405511Y389433D01*
X405400Y389641D01*
X405303Y389793D01*
X405220Y389918D01*
X405165Y389987D01*
X405137Y390015D01*
X404929Y390195D01*
X404693Y390334D01*
X404471Y390431D01*
X404249Y390500D01*
X404055Y390542D01*
X403903Y390556D01*
X403847Y390570D01*
D02*
G37*
G36*
X135998Y358766D02*
X135915D01*
X135624Y358738D01*
X135360Y358669D01*
X135138Y358586D01*
X134944Y358475D01*
X134792Y358364D01*
X134681Y358281D01*
X134611Y358211D01*
X134584Y358184D01*
X134403Y357948D01*
X134265Y357698D01*
X134168Y357435D01*
X134112Y357185D01*
X134071Y356963D01*
X134057Y356866D01*
Y356783D01*
X134043Y356713D01*
Y356658D01*
Y356630D01*
Y356616D01*
X134071Y356242D01*
X134126Y355923D01*
X134209Y355646D01*
X134306Y355410D01*
X134417Y355230D01*
X134500Y355091D01*
X134556Y355008D01*
X134584Y354994D01*
Y354980D01*
X134681Y354869D01*
X134792Y354786D01*
X135014Y354633D01*
X135236Y354536D01*
X135430Y354453D01*
X135610Y354411D01*
X135749Y354398D01*
X135804Y354384D01*
X135873D01*
X136068Y354398D01*
X136248Y354425D01*
X136414Y354481D01*
X136553Y354536D01*
X136678Y354578D01*
X136775Y354633D01*
X136830Y354661D01*
X136858Y354675D01*
X137024Y354800D01*
X137163Y354925D01*
X137288Y355077D01*
X137385Y355202D01*
X137468Y355327D01*
X137524Y355424D01*
X137565Y355493D01*
X137579Y355521D01*
X137662Y355729D01*
X137718Y355937D01*
X137773Y356131D01*
X137801Y356311D01*
X137815Y356464D01*
X137829Y356589D01*
Y356658D01*
Y356686D01*
X137801Y357019D01*
X137746Y357310D01*
X137649Y357573D01*
X137551Y357781D01*
X137454Y357962D01*
X137357Y358087D01*
X137302Y358156D01*
X137274Y358184D01*
X137052Y358378D01*
X136830Y358516D01*
X136595Y358627D01*
X136386Y358697D01*
X136192Y358738D01*
X136054Y358752D01*
X135998Y358766D01*
D02*
G37*
G36*
X42069Y207724D02*
X39323D01*
X39073Y207710D01*
X38865Y207696D01*
X38699Y207682D01*
X38588Y207654D01*
X38505Y207640D01*
X38449Y207627D01*
X38435D01*
X38255Y207557D01*
X38103Y207474D01*
X37964Y207391D01*
X37839Y207294D01*
X37756Y207197D01*
X37686Y207127D01*
X37645Y207072D01*
X37631Y207058D01*
X37534Y206892D01*
X37451Y206725D01*
X37395Y206545D01*
X37367Y206392D01*
X37340Y206254D01*
X37326Y206129D01*
Y206059D01*
Y206046D01*
Y206032D01*
X37354Y205741D01*
X37409Y205491D01*
X37492Y205269D01*
X37589Y205089D01*
X37686Y204950D01*
X37770Y204839D01*
X37825Y204784D01*
X37853Y204756D01*
X37950Y204673D01*
X38075Y204603D01*
X38338Y204492D01*
X38630Y204409D01*
X38921Y204354D01*
X39184Y204326D01*
X39295Y204312D01*
X39392D01*
X39489Y204298D01*
X42069D01*
Y207724D01*
D02*
G37*
G36*
X24387Y207932D02*
X24303D01*
X24151Y207918D01*
X23998Y207904D01*
X23860Y207862D01*
X23735Y207807D01*
X23499Y207682D01*
X23291Y207543D01*
X23138Y207391D01*
X23014Y207266D01*
X22972Y207211D01*
X22944Y207169D01*
X22917Y207155D01*
Y207141D01*
X22819Y206975D01*
X22736Y206781D01*
X22653Y206559D01*
X22598Y206323D01*
X22542Y206073D01*
X22501Y205810D01*
X22431Y205283D01*
X22403Y205019D01*
X22390Y204784D01*
X22376Y204562D01*
Y204381D01*
X22362Y204215D01*
Y204090D01*
Y204021D01*
Y204007D01*
Y203993D01*
Y203563D01*
X22390Y203175D01*
X22417Y202828D01*
X22445Y202495D01*
X22487Y202218D01*
X22542Y201954D01*
X22598Y201733D01*
X22639Y201525D01*
X22695Y201358D01*
X22750Y201219D01*
X22792Y201095D01*
X22847Y200998D01*
X22875Y200928D01*
X22903Y200886D01*
X22930Y200859D01*
Y200845D01*
X23041Y200706D01*
X23152Y200595D01*
X23263Y200484D01*
X23374Y200401D01*
X23610Y200263D01*
X23818Y200165D01*
X24012Y200110D01*
X24151Y200082D01*
X24206Y200068D01*
X24290D01*
X24442Y200082D01*
X24581Y200096D01*
X24844Y200193D01*
X25080Y200318D01*
X25288Y200457D01*
X25441Y200595D01*
X25565Y200720D01*
X25635Y200817D01*
X25663Y200831D01*
Y200845D01*
X25760Y201011D01*
X25843Y201206D01*
X25926Y201427D01*
X25982Y201663D01*
X26037Y201913D01*
X26079Y202176D01*
X26148Y202717D01*
X26176Y202967D01*
X26189Y203203D01*
X26203Y203424D01*
Y203605D01*
X26217Y203771D01*
Y203896D01*
Y203965D01*
Y203993D01*
X26203Y204423D01*
X26189Y204811D01*
X26162Y205172D01*
X26120Y205505D01*
X26079Y205796D01*
X26023Y206059D01*
X25968Y206295D01*
X25912Y206503D01*
X25857Y206684D01*
X25815Y206836D01*
X25760Y206961D01*
X25718Y207072D01*
X25676Y207141D01*
X25649Y207197D01*
X25621Y207224D01*
Y207238D01*
X25524Y207363D01*
X25427Y207474D01*
X25316Y207557D01*
X25205Y207640D01*
X24983Y207765D01*
X24775Y207848D01*
X24595Y207890D01*
X24442Y207918D01*
X24387Y207932D01*
D02*
G37*
G36*
X57137Y27799D02*
X54391D01*
X54141Y27785D01*
X53933Y27771D01*
X53767Y27757D01*
X53656Y27730D01*
X53573Y27716D01*
X53517Y27702D01*
X53503D01*
X53323Y27633D01*
X53170Y27549D01*
X53032Y27466D01*
X52907Y27369D01*
X52824Y27272D01*
X52754Y27203D01*
X52713Y27147D01*
X52699Y27133D01*
X52602Y26967D01*
X52519Y26801D01*
X52463Y26620D01*
X52435Y26468D01*
X52408Y26329D01*
X52394Y26204D01*
Y26135D01*
Y26121D01*
Y26107D01*
X52421Y25816D01*
X52477Y25566D01*
X52560Y25344D01*
X52657Y25164D01*
X52754Y25025D01*
X52838Y24915D01*
X52893Y24859D01*
X52921Y24831D01*
X53018Y24748D01*
X53143Y24679D01*
X53406Y24568D01*
X53697Y24485D01*
X53989Y24429D01*
X54252Y24401D01*
X54363Y24388D01*
X54460D01*
X54557Y24374D01*
X57137D01*
Y27799D01*
D02*
G37*
G36*
X463081Y281310D02*
X460335D01*
X460086Y281296D01*
X459878Y281282D01*
X459711Y281268D01*
X459600Y281240D01*
X459517Y281227D01*
X459462Y281213D01*
X459448D01*
X459268Y281143D01*
X459115Y281060D01*
X458976Y280977D01*
X458851Y280880D01*
X458768Y280783D01*
X458699Y280713D01*
X458657Y280658D01*
X458643Y280644D01*
X458546Y280478D01*
X458463Y280311D01*
X458408Y280131D01*
X458380Y279978D01*
X458352Y279840D01*
X458338Y279715D01*
Y279646D01*
Y279632D01*
Y279618D01*
X458366Y279326D01*
X458422Y279077D01*
X458505Y278855D01*
X458602Y278675D01*
X458699Y278536D01*
X458782Y278425D01*
X458838Y278370D01*
X458865Y278342D01*
X458962Y278259D01*
X459087Y278189D01*
X459351Y278078D01*
X459642Y277995D01*
X459933Y277940D01*
X460197Y277912D01*
X460308Y277898D01*
X460405D01*
X460502Y277884D01*
X463081D01*
Y281310D01*
D02*
G37*
G36*
X452125Y280533D02*
Y276234D01*
X455149D01*
X452125Y280533D01*
D02*
G37*
G36*
X41034Y484201D02*
X40951D01*
X40660Y484173D01*
X40396Y484104D01*
X40174Y484020D01*
X39980Y483909D01*
X39827Y483798D01*
X39716Y483715D01*
X39647Y483646D01*
X39619Y483618D01*
X39439Y483382D01*
X39300Y483133D01*
X39203Y482869D01*
X39148Y482620D01*
X39106Y482398D01*
X39092Y482301D01*
Y482218D01*
X39079Y482148D01*
Y482093D01*
Y482065D01*
Y482051D01*
X39106Y481677D01*
X39162Y481358D01*
X39245Y481080D01*
X39342Y480845D01*
X39453Y480664D01*
X39536Y480526D01*
X39592Y480442D01*
X39619Y480429D01*
Y480415D01*
X39716Y480304D01*
X39827Y480220D01*
X40049Y480068D01*
X40271Y479971D01*
X40465Y479888D01*
X40646Y479846D01*
X40784Y479832D01*
X40840Y479818D01*
X40909D01*
X41103Y479832D01*
X41284Y479860D01*
X41450Y479915D01*
X41589Y479971D01*
X41714Y480013D01*
X41811Y480068D01*
X41866Y480096D01*
X41894Y480110D01*
X42060Y480234D01*
X42199Y480359D01*
X42324Y480512D01*
X42421Y480637D01*
X42504Y480761D01*
X42559Y480858D01*
X42601Y480928D01*
X42615Y480956D01*
X42698Y481164D01*
X42754Y481372D01*
X42809Y481566D01*
X42837Y481746D01*
X42851Y481899D01*
X42865Y482023D01*
Y482093D01*
Y482121D01*
X42837Y482453D01*
X42781Y482745D01*
X42684Y483008D01*
X42587Y483216D01*
X42490Y483396D01*
X42393Y483521D01*
X42338Y483591D01*
X42310Y483618D01*
X42088Y483812D01*
X41866Y483951D01*
X41630Y484062D01*
X41422Y484131D01*
X41228Y484173D01*
X41090Y484187D01*
X41034Y484201D01*
D02*
G37*
G36*
X51352Y487474D02*
X48606D01*
X48356Y487460D01*
X48148Y487446D01*
X47982Y487432D01*
X47871Y487404D01*
X47788Y487391D01*
X47732Y487377D01*
X47719D01*
X47538Y487307D01*
X47386Y487224D01*
X47247Y487141D01*
X47122Y487044D01*
X47039Y486947D01*
X46970Y486877D01*
X46928Y486822D01*
X46914Y486808D01*
X46817Y486642D01*
X46734Y486475D01*
X46678Y486295D01*
X46651Y486142D01*
X46623Y486004D01*
X46609Y485879D01*
Y485810D01*
Y485796D01*
Y485782D01*
X46637Y485490D01*
X46692Y485241D01*
X46775Y485019D01*
X46873Y484839D01*
X46970Y484700D01*
X47053Y484589D01*
X47108Y484534D01*
X47136Y484506D01*
X47233Y484423D01*
X47358Y484353D01*
X47621Y484242D01*
X47913Y484159D01*
X48204Y484104D01*
X48467Y484076D01*
X48578Y484062D01*
X48675D01*
X48773Y484048D01*
X51352D01*
Y487474D01*
D02*
G37*
G36*
X149503Y455790D02*
X149420D01*
X149406D01*
X149392D01*
X149170Y455776D01*
X148962Y455721D01*
X148782Y455651D01*
X148630Y455568D01*
X148505Y455485D01*
X148421Y455416D01*
X148352Y455360D01*
X148338Y455346D01*
X148200Y455180D01*
X148089Y454986D01*
X148019Y454805D01*
X147964Y454625D01*
X147936Y454459D01*
X147922Y454334D01*
X147908Y454251D01*
Y454223D01*
X147922Y453973D01*
X147978Y453751D01*
X148047Y453557D01*
X148130Y453391D01*
X148200Y453266D01*
X148269Y453169D01*
X148324Y453100D01*
X148338Y453086D01*
X148505Y452947D01*
X148699Y452836D01*
X148879Y452767D01*
X149059Y452711D01*
X149212Y452683D01*
X149337Y452670D01*
X149420Y452656D01*
X149434D01*
X149448D01*
X149670Y452670D01*
X149864Y452725D01*
X150044Y452794D01*
X150197Y452878D01*
X150322Y452947D01*
X150419Y453016D01*
X150474Y453072D01*
X150488Y453086D01*
X150640Y453266D01*
X150751Y453446D01*
X150821Y453640D01*
X150876Y453821D01*
X150904Y453987D01*
X150932Y454112D01*
Y454223D01*
X150918Y454459D01*
X150862Y454680D01*
X150793Y454861D01*
X150710Y455027D01*
X150627Y455152D01*
X150557Y455249D01*
X150502Y455318D01*
X150488Y455332D01*
X150308Y455485D01*
X150127Y455596D01*
X149947Y455679D01*
X149781Y455734D01*
X149628Y455762D01*
X149503Y455790D01*
D02*
G37*
G36*
X145065Y456178D02*
X145024D01*
X144996D01*
X144982D01*
X144691Y456151D01*
X144414Y456095D01*
X144178Y455998D01*
X143984Y455901D01*
X143831Y455804D01*
X143706Y455707D01*
X143637Y455651D01*
X143609Y455624D01*
X143429Y455402D01*
X143290Y455180D01*
X143207Y454944D01*
X143138Y454722D01*
X143096Y454528D01*
X143082Y454362D01*
X143068Y454306D01*
Y454223D01*
X143082Y454029D01*
X143110Y453835D01*
X143152Y453654D01*
X143193Y453502D01*
X143235Y453377D01*
X143276Y453280D01*
X143304Y453224D01*
X143318Y453197D01*
X143429Y453030D01*
X143540Y452892D01*
X143665Y452767D01*
X143790Y452670D01*
X143887Y452586D01*
X143970Y452531D01*
X144039Y452503D01*
X144053Y452489D01*
X144233Y452420D01*
X144400Y452365D01*
X144566Y452323D01*
X144719Y452295D01*
X144844Y452281D01*
X144941Y452267D01*
X144996D01*
X145024D01*
X145315Y452295D01*
X145578Y452351D01*
X145814Y452434D01*
X146022Y452545D01*
X146175Y452642D01*
X146300Y452725D01*
X146369Y452781D01*
X146397Y452808D01*
X146577Y453016D01*
X146716Y453252D01*
X146813Y453474D01*
X146882Y453696D01*
X146924Y453890D01*
X146938Y454043D01*
X146952Y454098D01*
Y454181D01*
X146924Y454486D01*
X146868Y454764D01*
X146771Y455013D01*
X146674Y455221D01*
X146563Y455388D01*
X146466Y455513D01*
X146411Y455582D01*
X146383Y455610D01*
X146161Y455804D01*
X145925Y455943D01*
X145689Y456040D01*
X145481Y456109D01*
X145273Y456151D01*
X145121Y456165D01*
X145065Y456178D01*
D02*
G37*
G36*
X149129Y448634D02*
X149059D01*
X149046D01*
X149032D01*
X148741Y448606D01*
X148491Y448551D01*
X148269Y448467D01*
X148089Y448370D01*
X147950Y448273D01*
X147839Y448190D01*
X147784Y448135D01*
X147756Y448107D01*
X147673Y448010D01*
X147603Y447885D01*
X147492Y447621D01*
X147409Y447330D01*
X147354Y447039D01*
X147326Y446776D01*
X147312Y446665D01*
Y446567D01*
X147298Y446470D01*
Y443891D01*
X150724D01*
Y446637D01*
X150710Y446886D01*
X150696Y447094D01*
X150682Y447261D01*
X150654Y447372D01*
X150640Y447455D01*
X150627Y447511D01*
Y447524D01*
X150557Y447705D01*
X150474Y447857D01*
X150391Y447996D01*
X150294Y448121D01*
X150197Y448204D01*
X150127Y448273D01*
X150072Y448315D01*
X150058Y448329D01*
X149892Y448426D01*
X149725Y448509D01*
X149545Y448565D01*
X149392Y448592D01*
X149254Y448620D01*
X149129Y448634D01*
D02*
G37*
G36*
X161316Y448641D02*
X161247D01*
X161233D01*
X161219D01*
X160928Y448613D01*
X160678Y448558D01*
X160457Y448474D01*
X160276Y448377D01*
X160138Y448280D01*
X160027Y448197D01*
X159971Y448142D01*
X159943Y448114D01*
X159860Y448017D01*
X159791Y447892D01*
X159680Y447628D01*
X159597Y447337D01*
X159541Y447046D01*
X159514Y446782D01*
X159500Y446671D01*
Y446574D01*
X159486Y446477D01*
Y443898D01*
X162911D01*
Y446644D01*
X162897Y446893D01*
X162883Y447101D01*
X162870Y447268D01*
X162842Y447379D01*
X162828Y447462D01*
X162814Y447518D01*
Y447531D01*
X162745Y447712D01*
X162662Y447864D01*
X162578Y448003D01*
X162481Y448128D01*
X162384Y448211D01*
X162315Y448280D01*
X162259Y448322D01*
X162246Y448336D01*
X162079Y448433D01*
X161913Y448516D01*
X161732Y448572D01*
X161580Y448599D01*
X161441Y448627D01*
X161316Y448641D01*
D02*
G37*
G36*
X463102Y484480D02*
X460356D01*
X460107Y484466D01*
X459898Y484452D01*
X459732Y484439D01*
X459621Y484411D01*
X459538Y484397D01*
X459482Y484383D01*
X459469D01*
X459288Y484314D01*
X459136Y484230D01*
X458997Y484147D01*
X458872Y484050D01*
X458789Y483953D01*
X458720Y483884D01*
X458678Y483828D01*
X458664Y483815D01*
X458567Y483648D01*
X458484Y483482D01*
X458428Y483301D01*
X458401Y483149D01*
X458373Y483010D01*
X458359Y482885D01*
Y482816D01*
Y482802D01*
Y482788D01*
X458387Y482497D01*
X458442Y482247D01*
X458526Y482025D01*
X458623Y481845D01*
X458720Y481707D01*
X458803Y481595D01*
X458858Y481540D01*
X458886Y481512D01*
X458983Y481429D01*
X459108Y481360D01*
X459371Y481249D01*
X459663Y481166D01*
X459954Y481110D01*
X460218Y481082D01*
X460328Y481068D01*
X460425D01*
X460523Y481055D01*
X463102D01*
Y484480D01*
D02*
G37*
G36*
X462173Y29900D02*
X459427D01*
X459177Y29886D01*
X458969Y29872D01*
X458803Y29858D01*
X458692Y29831D01*
X458609Y29817D01*
X458553Y29803D01*
X458539D01*
X458359Y29734D01*
X458207Y29650D01*
X458068Y29567D01*
X457943Y29470D01*
X457860Y29373D01*
X457790Y29304D01*
X457749Y29248D01*
X457735Y29234D01*
X457638Y29068D01*
X457555Y28902D01*
X457499Y28721D01*
X457472Y28569D01*
X457444Y28430D01*
X457430Y28305D01*
Y28236D01*
Y28222D01*
Y28208D01*
X457458Y27917D01*
X457513Y27667D01*
X457596Y27445D01*
X457693Y27265D01*
X457790Y27126D01*
X457874Y27015D01*
X457929Y26960D01*
X457957Y26932D01*
X458054Y26849D01*
X458179Y26780D01*
X458442Y26669D01*
X458734Y26585D01*
X459025Y26530D01*
X459288Y26502D01*
X459399Y26488D01*
X459496D01*
X459593Y26474D01*
X462173D01*
Y29900D01*
D02*
G37*
G36*
X31804Y460640D02*
X29058D01*
X28808Y460627D01*
X28600Y460613D01*
X28433Y460599D01*
X28323Y460571D01*
X28239Y460557D01*
X28184Y460543D01*
X28170D01*
X27990Y460474D01*
X27837Y460391D01*
X27699Y460308D01*
X27574Y460210D01*
X27490Y460113D01*
X27421Y460044D01*
X27380Y459989D01*
X27366Y459975D01*
X27269Y459808D01*
X27185Y459642D01*
X27130Y459462D01*
X27102Y459309D01*
X27074Y459170D01*
X27061Y459046D01*
Y458976D01*
Y458962D01*
Y458949D01*
X27088Y458657D01*
X27144Y458408D01*
X27227Y458186D01*
X27324Y458005D01*
X27421Y457867D01*
X27504Y457756D01*
X27560Y457700D01*
X27588Y457673D01*
X27685Y457589D01*
X27810Y457520D01*
X28073Y457409D01*
X28364Y457326D01*
X28655Y457270D01*
X28919Y457243D01*
X29030Y457229D01*
X29127D01*
X29224Y457215D01*
X31804D01*
Y460640D01*
D02*
G37*
%LPD*%
D11*
X119000Y200093D02*
G03*
X119000Y200093I-1500J0D01*
G01*
X173217Y327167D02*
G03*
X173217Y327167I-1500J0D01*
G01*
D14*
X71618Y364939D02*
X115618D01*
X71618Y396939D02*
X115618D01*
X125500Y260300D02*
X163500D01*
X125500Y208300D02*
X163500D01*
X276414Y356275D02*
X306414D01*
X276414Y380275D02*
X306414D01*
X40000Y292000D02*
X68000D01*
X40000Y216000D02*
X68000D01*
X125250Y319500D02*
X163250D01*
X125250Y267500D02*
X163250D01*
D73*
X53118Y371189D02*
G03*
X53118Y371189I-1500J0D01*
G01*
X268914Y360775D02*
G03*
X268914Y360775I-1500J0D01*
G01*
D101*
X207250Y34500D02*
D03*
M02*
